(lib_symbols
	(symbol "+5V_1"
			(power)
			(pin_numbers
				(hide yes)
			)
			(pin_names
				(hide yes)
			)
			(exclude_from_sim no)
			(in_bom yes)
			(on_board yes)
			(property "Reference" "#PWR"
				(at 15.24 -2.54 0)
				(effects
					(font
						(size 1.27 1.27)
						(thickness 0.15)
					)
					(justify left bottom)
					(hide yes)
				)
			)
			(property "Value" "+5V"
				(at 15.24 -5.08 0)
				(effects
					(font
						(size 1.27 1.27)
						(thickness 0.15)
					)
					(justify left bottom)
				)
			)
			(property "Footprint" ""
				(at 15.24 -7.62 0)
				(effects
					(font
						(size 1.27 1.27)
						(thickness 0.15)
					)
					(justify left bottom)
					(hide yes)
				)
			)
			(property "Datasheet" ""
				(at 15.24 -10.16 0)
				(effects
					(font
						(size 1.27 1.27)
						(thickness 0.15)
					)
					(justify left bottom)
					(hide yes)
				)
			)
			(property "Description" ""
				(at 15.24 -12.7 0)
				(effects
					(font
						(size 1.27 1.27)
					)
					(justify left bottom)
					(hide yes)
				)
			)
			(property "Author" "Antmicro"
				(at 15.24 -7.62 0)
				(effects
					(font
						(size 1.27 1.27)
						(thickness 0.15)
					)
					(justify left bottom)
					(hide yes)
				)
			)
			(property "License" "Apache-2.0"
				(at 15.24 -10.16 0)
				(effects
					(font
						(size 1.27 1.27)
						(thickness 0.15)
					)
					(justify left bottom)
					(hide yes)
				)
			)
			(symbol "+5V_1_1_1"
				(polyline
					(pts
						(xy -0.762 1.27) (xy 0 2.54)
					)
					(stroke
						(width 0)
						(type default)
					)
					(fill
						(type background)
					)
				)
				(polyline
					(pts
						(xy 0 2.54) (xy 0.762 1.27)
					)
					(stroke
						(width 0)
						(type default)
					)
					(fill
						(type background)
					)
				)
				(polyline
					(pts
						(xy 0 0) (xy 0 2.54)
					)
					(stroke
						(width 0)
						(type default)
					)
					(fill
						(type background)
					)
				)
				(pin power_in line
					(at 0 0 90)
					(length 0)
					(name "+5V"
						(effects
							(font
								(size 1.27 1.27)
							)
						)
					)
					(number "1"
						(effects
							(font
								(size 1.27 1.27)
							)
						)
					)
				)
			)
		)
	(symbol "C_100n_0402_1"
			(pin_numbers
				(hide yes)
			)
			(pin_names
				(hide yes)
			)
			(exclude_from_sim no)
			(in_bom yes)
			(on_board yes)
			(property "Reference" "C"
				(at 20.32 -5.08 0)
				(effects
					(font
						(size 1.27 1.27)
						(thickness 0.15)
					)
					(justify left bottom)
				)
			)
			(property "Value" "C_100n_0402"
				(at 20.32 -10.16 0)
				(effects
					(font
						(size 1.27 1.27)
						(thickness 0.15)
					)
					(justify left bottom)
					(hide yes)
				)
			)
			(property "Footprint" "antmicro-footprints:C_0402_1005Metric"
				(at 20.32 -12.7 0)
				(effects
					(font
						(size 1.27 1.27)
						(thickness 0.15)
					)
					(justify left bottom)
					(hide yes)
				)
			)
			(property "Datasheet" "https://www.murata.com/products/productdetail?partno=GRM155R61H104KE14%23"
				(at 20.32 -15.24 0)
				(effects
					(font
						(size 1.27 1.27)
						(thickness 0.15)
					)
					(justify left bottom)
					(hide yes)
				)
			)
			(property "Description" "SMD Multilayer Ceramic Capacitor, 0.1 µF, 50 V, 0402 [1005 Metric], ± 10%, X5R, GRM Series"
				(at 20.32 -33.02 0)
				(effects
					(font
						(size 1.27 1.27)
					)
					(justify left bottom)
					(hide yes)
				)
			)
			(property "MPN" "GRM155R61H104KE14D"
				(at 20.32 -17.78 0)
				(effects
					(font
						(size 1.27 1.27)
						(thickness 0.15)
					)
					(justify left bottom)
					(hide yes)
				)
			)
			(property "Manufacturer" "Murata"
				(at 20.32 -20.32 0)
				(effects
					(font
						(size 1.27 1.27)
						(thickness 0.15)
					)
					(justify left bottom)
					(hide yes)
				)
			)
			(property "License" "Apache-2.0"
				(at 20.32 -22.86 0)
				(effects
					(font
						(size 1.27 1.27)
						(thickness 0.15)
					)
					(justify left bottom)
					(hide yes)
				)
			)
			(property "Author" "Antmicro"
				(at 20.32 -25.4 0)
				(effects
					(font
						(size 1.27 1.27)
						(thickness 0.15)
					)
					(justify left bottom)
					(hide yes)
				)
			)
			(property "Val" "100n"
				(at 20.32 -7.62 0)
				(effects
					(font
						(size 1.27 1.27)
						(thickness 0.15)
					)
					(justify left bottom)
				)
			)
			(property "Voltage" "50V"
				(at 20.32 -27.94 0)
				(effects
					(font
						(size 1.27 1.27)
					)
					(justify left bottom)
					(hide yes)
				)
			)
			(property "Dielectric" "X5R"
				(at 20.32 -30.48 0)
				(effects
					(font
						(size 1.27 1.27)
					)
					(justify left bottom)
					(hide yes)
				)
			)
			(property "ki_keywords" "0402, SMT, CAPACITOR, PASSIVE, CERAMIC, MLCC"
				(at 0 0 0)
				(effects
					(font
						(size 1.27 1.27)
					)
					(hide yes)
				)
			)
			(symbol "C_100n_0402_1_0_1"
				(polyline
					(pts
						(xy 2.032 -1.524) (xy 2.032 1.524)
					)
					(stroke
						(width 0.3048)
						(type default)
					)
					(fill
						(type none)
					)
				)
				(polyline
					(pts
						(xy 3.048 -1.524) (xy 3.048 1.524)
					)
					(stroke
						(width 0.3302)
						(type default)
					)
					(fill
						(type none)
					)
				)
			)
			(symbol "C_100n_0402_1_1_1"
				(pin passive line
					(at 0 0 0)
					(length 2.032)
					(name "~"
						(effects
							(font
								(size 1.27 1.27)
							)
						)
					)
					(number "1"
						(effects
							(font
								(size 1.27 1.27)
							)
						)
					)
				)
				(pin passive line
					(at 5.08 0 180)
					(length 2.032)
					(name "~"
						(effects
							(font
								(size 1.27 1.27)
							)
						)
					)
					(number "2"
						(effects
							(font
								(size 1.27 1.27)
							)
						)
					)
				)
			)
		)
	(symbol "R_0R_0402_1"
			(pin_numbers
				(hide yes)
			)
			(pin_names
				(hide yes)
			)
			(exclude_from_sim no)
			(in_bom yes)
			(on_board yes)
			(property "Reference" "R"
				(at 20.32 -5.08 0)
				(effects
					(font
						(size 1.27 1.27)
						(thickness 0.15)
					)
					(justify left bottom)
				)
			)
			(property "Value" "R_0R_0402"
				(at 20.32 -12.7 0)
				(effects
					(font
						(size 1.27 1.27)
						(thickness 0.15)
					)
					(justify left bottom)
					(hide yes)
				)
			)
			(property "Footprint" "antmicro-footprints:R_0402_1005Metric"
				(at 20.32 -15.24 0)
				(effects
					(font
						(size 1.27 1.27)
						(thickness 0.15)
					)
					(justify left bottom)
					(hide yes)
				)
			)
			(property "Datasheet" "https://industrial.panasonic.com/cdbs/www-data/pdf/RDA0000/AOA0000C301.pdf"
				(at 20.32 -17.78 0)
				(effects
					(font
						(size 1.27 1.27)
						(thickness 0.15)
					)
					(justify left bottom)
					(hide yes)
				)
			)
			(property "Description" "SMD Chip Resistor, Jumper, 0 ohm, 100 mW, 0402 [1005 Metric], Thick Film, General Purpose"
				(at 20.32 -33.02 0)
				(effects
					(font
						(size 1.27 1.27)
					)
					(justify left bottom)
					(hide yes)
				)
			)
			(property "MPN" "ERJ2GE0R00X"
				(at 20.32 -20.32 0)
				(effects
					(font
						(size 1.27 1.27)
						(thickness 0.15)
					)
					(justify left bottom)
					(hide yes)
				)
			)
			(property "Manufacturer" "Panasonic"
				(at 20.32 -22.86 0)
				(effects
					(font
						(size 1.27 1.27)
						(thickness 0.15)
					)
					(justify left bottom)
					(hide yes)
				)
			)
			(property "License" "Apache-2.0"
				(at 20.32 -25.4 0)
				(effects
					(font
						(size 1.27 1.27)
						(thickness 0.15)
					)
					(justify left bottom)
					(hide yes)
				)
			)
			(property "Author" "Antmicro"
				(at 20.32 -27.94 0)
				(effects
					(font
						(size 1.27 1.27)
						(thickness 0.15)
					)
					(justify left bottom)
					(hide yes)
				)
			)
			(property "Val" "0R"
				(at 20.32 -7.62 0)
				(effects
					(font
						(size 1.27 1.27)
						(thickness 0.15)
					)
					(justify left bottom)
				)
			)
			(property "Tolerance" "~"
				(at 20.32 -10.16 0)
				(effects
					(font
						(size 1.27 1.27)
					)
					(justify left bottom)
					(hide yes)
				)
			)
			(property "Current" "1A"
				(at 20.32 -30.48 0)
				(effects
					(font
						(size 1.27 1.27)
						(thickness 0.15)
					)
					(justify left bottom)
					(hide yes)
				)
			)
			(property "ki_keywords" "0402, SMT, RESISTOR, PASSIVE"
				(at 0 0 0)
				(effects
					(font
						(size 1.27 1.27)
					)
					(hide yes)
				)
			)
			(symbol "R_0R_0402_1_0_1"
				(rectangle
					(start 0.635 0.889)
					(end 4.445 -0.889)
					(stroke
						(width 0.254)
						(type default)
					)
					(fill
						(type none)
					)
				)
			)
			(symbol "R_0R_0402_1_1_1"
				(pin passive line
					(at 0 0 0)
					(length 0.635)
					(name "~"
						(effects
							(font
								(size 1.27 1.27)
							)
						)
					)
					(number "1"
						(effects
							(font
								(size 1.27 1.27)
							)
						)
					)
				)
				(pin passive line
					(at 5.08 0 180)
					(length 0.635)
					(name "~"
						(effects
							(font
								(size 1.27 1.27)
							)
						)
					)
					(number "2"
						(effects
							(font
								(size 1.27 1.27)
							)
						)
					)
				)
			)
		)
	(symbol "R_0R_0402_2"
			(pin_numbers
				(hide yes)
			)
			(pin_names
				(hide yes)
			)
			(exclude_from_sim no)
			(in_bom yes)
			(on_board yes)
			(property "Reference" "R"
				(at 20.32 -5.08 0)
				(effects
					(font
						(size 1.27 1.27)
						(thickness 0.15)
					)
					(justify left bottom)
				)
			)
			(property "Value" "R_0R_0402"
				(at 20.32 -12.7 0)
				(effects
					(font
						(size 1.27 1.27)
						(thickness 0.15)
					)
					(justify left bottom)
					(hide yes)
				)
			)
			(property "Footprint" "antmicro-footprints:R_0402_1005Metric"
				(at 20.32 -15.24 0)
				(effects
					(font
						(size 1.27 1.27)
						(thickness 0.15)
					)
					(justify left bottom)
					(hide yes)
				)
			)
			(property "Datasheet" "https://industrial.panasonic.com/cdbs/www-data/pdf/RDA0000/AOA0000C301.pdf"
				(at 20.32 -17.78 0)
				(effects
					(font
						(size 1.27 1.27)
						(thickness 0.15)
					)
					(justify left bottom)
					(hide yes)
				)
			)
			(property "Description" "SMD Chip Resistor, Jumper, 0 ohm, 100 mW, 0402 [1005 Metric], Thick Film, General Purpose"
				(at 20.32 -33.02 0)
				(effects
					(font
						(size 1.27 1.27)
					)
					(justify left bottom)
					(hide yes)
				)
			)
			(property "MPN" "ERJ2GE0R00X"
				(at 20.32 -20.32 0)
				(effects
					(font
						(size 1.27 1.27)
						(thickness 0.15)
					)
					(justify left bottom)
					(hide yes)
				)
			)
			(property "Manufacturer" "Panasonic"
				(at 20.32 -22.86 0)
				(effects
					(font
						(size 1.27 1.27)
						(thickness 0.15)
					)
					(justify left bottom)
					(hide yes)
				)
			)
			(property "License" "Apache-2.0"
				(at 20.32 -25.4 0)
				(effects
					(font
						(size 1.27 1.27)
						(thickness 0.15)
					)
					(justify left bottom)
					(hide yes)
				)
			)
			(property "Author" "Antmicro"
				(at 20.32 -27.94 0)
				(effects
					(font
						(size 1.27 1.27)
						(thickness 0.15)
					)
					(justify left bottom)
					(hide yes)
				)
			)
			(property "Val" "0R"
				(at 20.32 -7.62 0)
				(effects
					(font
						(size 1.27 1.27)
						(thickness 0.15)
					)
					(justify left bottom)
				)
			)
			(property "Tolerance" "~"
				(at 20.32 -10.16 0)
				(effects
					(font
						(size 1.27 1.27)
					)
					(justify left bottom)
					(hide yes)
				)
			)
			(property "Current" "1A"
				(at 20.32 -30.48 0)
				(effects
					(font
						(size 1.27 1.27)
						(thickness 0.15)
					)
					(justify left bottom)
					(hide yes)
				)
			)
			(property "ki_keywords" "0402, SMT, RESISTOR, PASSIVE"
				(at 0 0 0)
				(effects
					(font
						(size 1.27 1.27)
					)
					(hide yes)
				)
			)
			(symbol "R_0R_0402_2_0_1"
				(rectangle
					(start 0.635 0.889)
					(end 4.445 -0.889)
					(stroke
						(width 0.254)
						(type default)
					)
					(fill
						(type none)
					)
				)
			)
			(symbol "R_0R_0402_2_1_1"
				(pin passive line
					(at 0 0 0)
					(length 0.635)
					(name "~"
						(effects
							(font
								(size 1.27 1.27)
							)
						)
					)
					(number "1"
						(effects
							(font
								(size 1.27 1.27)
							)
						)
					)
				)
				(pin passive line
					(at 5.08 0 180)
					(length 0.635)
					(name "~"
						(effects
							(font
								(size 1.27 1.27)
							)
						)
					)
					(number "2"
						(effects
							(font
								(size 1.27 1.27)
							)
						)
					)
				)
			)
		)
	(symbol "antmicroB2BConnectors:Socket_Hirose_DF40_2x50_DF40HC-3.0-100DS-0.4V"
			(exclude_from_sim no)
			(in_bom yes)
			(on_board yes)
			(property "Reference" "J"
				(at 35.56 0 0)
				(effects
					(font
						(size 1.27 1.27)
						(thickness 0.15)
					)
					(justify left bottom)
				)
			)
			(property "Value" "Socket_Hirose_DF40_2x50_DF40HC-3.0-100DS-0.4V"
				(at 35.56 -5.08 0)
				(effects
					(font
						(size 1.27 1.27)
						(thickness 0.15)
					)
					(justify left bottom)
					(hide yes)
				)
			)
			(property "Footprint" "antmicro-footprints:Conn_Socket_Hirose_DF40_2x50_DF40HC-3.0-100DS-0.4V"
				(at 35.56 -7.62 0)
				(effects
					(font
						(size 1.27 1.27)
						(thickness 0.15)
					)
					(justify left bottom)
					(hide yes)
				)
			)
			(property "Datasheet" "https://www.hirose.com/en/product/document?clcode=CL0684-4151-0-51&productname=DF40HC(3.0)-100DS-0.4V(51&series=DF40&documenttype=Catalog&lang=en&documentid=en_DF40_CAT"
				(at 35.56 -10.16 0)
				(effects
					(font
						(size 1.27 1.27)
						(thickness 0.15)
					)
					(justify left bottom)
					(hide yes)
				)
			)
			(property "Description" "100 Position Connector Receptacle, Center Strip Contacts Surface Mount Gold"
				(at 0 0 0)
				(effects
					(font
						(size 1.27 1.27)
					)
					(hide yes)
				)
			)
			(property "MPN" "DF40HC(3.0)-100DS-0.4V(51)"
				(at 35.56 -2.54 0)
				(effects
					(font
						(size 1.27 1.27)
						(thickness 0.15)
					)
					(justify left bottom)
				)
			)
			(property "Manufacturer" "Hirose Electric"
				(at 35.56 -12.7 0)
				(effects
					(font
						(size 1.27 1.27)
						(thickness 0.15)
					)
					(justify left bottom)
					(hide yes)
				)
			)
			(property "Pitch" "0.4 mm"
				(at 35.56 -15.24 0)
				(effects
					(font
						(size 1.27 1.27)
					)
					(justify left bottom)
					(hide yes)
				)
			)
			(property "Author" "Antmicro"
				(at 35.56 -17.78 0)
				(effects
					(font
						(size 1.27 1.27)
						(thickness 0.15)
					)
					(justify left bottom)
					(hide yes)
				)
			)
			(property "License" "Apache-2.0"
				(at 35.56 -20.32 0)
				(effects
					(font
						(size 1.27 1.27)
						(thickness 0.15)
					)
					(justify left bottom)
					(hide yes)
				)
			)
			(property "ki_keywords" "CONNECTOR, B2B, SOCKET"
				(at 0 0 0)
				(effects
					(font
						(size 1.27 1.27)
					)
					(hide yes)
				)
			)
			(symbol "Socket_Hirose_DF40_2x50_DF40HC-3.0-100DS-0.4V_1_1"
				(rectangle
					(start 3.81 2.54)
					(end 10.16 -127)
					(stroke
						(width 0.254)
						(type default)
					)
					(fill
						(type background)
					)
				)
				(rectangle
					(start 5.08 1.27)
					(end 8.89 -125.73)
					(stroke
						(width 0.254)
						(type default)
					)
					(fill
						(type background)
					)
				)
				(pin passive line
					(at 0 0 0)
					(length 3.81)
					(name "~"
						(effects
							(font
								(size 1.27 1.27)
							)
						)
					)
					(number "1"
						(effects
							(font
								(size 1.27 1.27)
							)
						)
					)
				)
				(pin passive line
					(at 0 -2.54 0)
					(length 3.81)
					(name "~"
						(effects
							(font
								(size 1.27 1.27)
							)
						)
					)
					(number "3"
						(effects
							(font
								(size 1.27 1.27)
							)
						)
					)
				)
				(pin passive line
					(at 0 -5.08 0)
					(length 3.81)
					(name "~"
						(effects
							(font
								(size 1.27 1.27)
							)
						)
					)
					(number "5"
						(effects
							(font
								(size 1.27 1.27)
							)
						)
					)
				)
				(pin passive line
					(at 0 -7.62 0)
					(length 3.81)
					(name "~"
						(effects
							(font
								(size 1.27 1.27)
							)
						)
					)
					(number "7"
						(effects
							(font
								(size 1.27 1.27)
							)
						)
					)
				)
				(pin passive line
					(at 0 -10.16 0)
					(length 3.81)
					(name "~"
						(effects
							(font
								(size 1.27 1.27)
							)
						)
					)
					(number "9"
						(effects
							(font
								(size 1.27 1.27)
							)
						)
					)
				)
				(pin passive line
					(at 0 -12.7 0)
					(length 3.81)
					(name "~"
						(effects
							(font
								(size 1.27 1.27)
							)
						)
					)
					(number "11"
						(effects
							(font
								(size 1.27 1.27)
							)
						)
					)
				)
				(pin passive line
					(at 0 -15.24 0)
					(length 3.81)
					(name "~"
						(effects
							(font
								(size 1.27 1.27)
							)
						)
					)
					(number "13"
						(effects
							(font
								(size 1.27 1.27)
							)
						)
					)
				)
				(pin passive line
					(at 0 -17.78 0)
					(length 3.81)
					(name "~"
						(effects
							(font
								(size 1.27 1.27)
							)
						)
					)
					(number "15"
						(effects
							(font
								(size 1.27 1.27)
							)
						)
					)
				)
				(pin passive line
					(at 0 -20.32 0)
					(length 3.81)
					(name "~"
						(effects
							(font
								(size 1.27 1.27)
							)
						)
					)
					(number "17"
						(effects
							(font
								(size 1.27 1.27)
							)
						)
					)
				)
				(pin passive line
					(at 0 -22.86 0)
					(length 3.81)
					(name "~"
						(effects
							(font
								(size 1.27 1.27)
							)
						)
					)
					(number "19"
						(effects
							(font
								(size 1.27 1.27)
							)
						)
					)
				)
				(pin passive line
					(at 0 -25.4 0)
					(length 3.81)
					(name "~"
						(effects
							(font
								(size 1.27 1.27)
							)
						)
					)
					(number "21"
						(effects
							(font
								(size 1.27 1.27)
							)
						)
					)
				)
				(pin passive line
					(at 0 -27.94 0)
					(length 3.81)
					(name "~"
						(effects
							(font
								(size 1.27 1.27)
							)
						)
					)
					(number "23"
						(effects
							(font
								(size 1.27 1.27)
							)
						)
					)
				)
				(pin passive line
					(at 0 -30.48 0)
					(length 3.81)
					(name "~"
						(effects
							(font
								(size 1.27 1.27)
							)
						)
					)
					(number "25"
						(effects
							(font
								(size 1.27 1.27)
							)
						)
					)
				)
				(pin passive line
					(at 0 -33.02 0)
					(length 3.81)
					(name "~"
						(effects
							(font
								(size 1.27 1.27)
							)
						)
					)
					(number "27"
						(effects
							(font
								(size 1.27 1.27)
							)
						)
					)
				)
				(pin passive line
					(at 0 -35.56 0)
					(length 3.81)
					(name "~"
						(effects
							(font
								(size 1.27 1.27)
							)
						)
					)
					(number "29"
						(effects
							(font
								(size 1.27 1.27)
							)
						)
					)
				)
				(pin passive line
					(at 0 -38.1 0)
					(length 3.81)
					(name "~"
						(effects
							(font
								(size 1.27 1.27)
							)
						)
					)
					(number "31"
						(effects
							(font
								(size 1.27 1.27)
							)
						)
					)
				)
				(pin passive line
					(at 0 -40.64 0)
					(length 3.81)
					(name "~"
						(effects
							(font
								(size 1.27 1.27)
							)
						)
					)
					(number "33"
						(effects
							(font
								(size 1.27 1.27)
							)
						)
					)
				)
				(pin passive line
					(at 0 -43.18 0)
					(length 3.81)
					(name "~"
						(effects
							(font
								(size 1.27 1.27)
							)
						)
					)
					(number "35"
						(effects
							(font
								(size 1.27 1.27)
							)
						)
					)
				)
				(pin passive line
					(at 0 -45.72 0)
					(length 3.81)
					(name "~"
						(effects
							(font
								(size 1.27 1.27)
							)
						)
					)
					(number "37"
						(effects
							(font
								(size 1.27 1.27)
							)
						)
					)
				)
				(pin passive line
					(at 0 -48.26 0)
					(length 3.81)
					(name "~"
						(effects
							(font
								(size 1.27 1.27)
							)
						)
					)
					(number "39"
						(effects
							(font
								(size 1.27 1.27)
							)
						)
					)
				)
				(pin passive line
					(at 0 -50.8 0)
					(length 3.81)
					(name "~"
						(effects
							(font
								(size 1.27 1.27)
							)
						)
					)
					(number "41"
						(effects
							(font
								(size 1.27 1.27)
							)
						)
					)
				)
				(pin passive line
					(at 0 -53.34 0)
					(length 3.81)
					(name "~"
						(effects
							(font
								(size 1.27 1.27)
							)
						)
					)
					(number "43"
						(effects
							(font
								(size 1.27 1.27)
							)
						)
					)
				)
				(pin passive line
					(at 0 -55.88 0)
					(length 3.81)
					(name "~"
						(effects
							(font
								(size 1.27 1.27)
							)
						)
					)
					(number "45"
						(effects
							(font
								(size 1.27 1.27)
							)
						)
					)
				)
				(pin passive line
					(at 0 -58.42 0)
					(length 3.81)
					(name "~"
						(effects
							(font
								(size 1.27 1.27)
							)
						)
					)
					(number "47"
						(effects
							(font
								(size 1.27 1.27)
							)
						)
					)
				)
				(pin passive line
					(at 0 -60.96 0)
					(length 3.81)
					(name "~"
						(effects
							(font
								(size 1.27 1.27)
							)
						)
					)
					(number "49"
						(effects
							(font
								(size 1.27 1.27)
							)
						)
					)
				)
				(pin passive line
					(at 0 -63.5 0)
					(length 3.81)
					(name "~"
						(effects
							(font
								(size 1.27 1.27)
							)
						)
					)
					(number "51"
						(effects
							(font
								(size 1.27 1.27)
							)
						)
					)
				)
				(pin passive line
					(at 0 -66.04 0)
					(length 3.81)
					(name "~"
						(effects
							(font
								(size 1.27 1.27)
							)
						)
					)
					(number "53"
						(effects
							(font
								(size 1.27 1.27)
							)
						)
					)
				)
				(pin passive line
					(at 0 -68.58 0)
					(length 3.81)
					(name "~"
						(effects
							(font
								(size 1.27 1.27)
							)
						)
					)
					(number "55"
						(effects
							(font
								(size 1.27 1.27)
							)
						)
					)
				)
				(pin passive line
					(at 0 -71.12 0)
					(length 3.81)
					(name "~"
						(effects
							(font
								(size 1.27 1.27)
							)
						)
					)
					(number "57"
						(effects
							(font
								(size 1.27 1.27)
							)
						)
					)
				)
				(pin passive line
					(at 0 -73.66 0)
					(length 3.81)
					(name "~"
						(effects
							(font
								(size 1.27 1.27)
							)
						)
					)
					(number "59"
						(effects
							(font
								(size 1.27 1.27)
							)
						)
					)
				)
				(pin passive line
					(at 0 -76.2 0)
					(length 3.81)
					(name "~"
						(effects
							(font
								(size 1.27 1.27)
							)
						)
					)
					(number "61"
						(effects
							(font
								(size 1.27 1.27)
							)
						)
					)
				)
				(pin passive line
					(at 0 -78.74 0)
					(length 3.81)
					(name "~"
						(effects
							(font
								(size 1.27 1.27)
							)
						)
					)
					(number "63"
						(effects
							(font
								(size 1.27 1.27)
							)
						)
					)
				)
				(pin passive line
					(at 0 -81.28 0)
					(length 3.81)
					(name "~"
						(effects
							(font
								(size 1.27 1.27)
							)
						)
					)
					(number "65"
						(effects
							(font
								(size 1.27 1.27)
							)
						)
					)
				)
				(pin passive line
					(at 0 -83.82 0)
					(length 3.81)
					(name "~"
						(effects
							(font
								(size 1.27 1.27)
							)
						)
					)
					(number "67"
						(effects
							(font
								(size 1.27 1.27)
							)
						)
					)
				)
				(pin passive line
					(at 0 -86.36 0)
					(length 3.81)
					(name "~"
						(effects
							(font
								(size 1.27 1.27)
							)
						)
					)
					(number "69"
						(effects
							(font
								(size 1.27 1.27)
							)
						)
					)
				)
				(pin passive line
					(at 0 -88.9 0)
					(length 3.81)
					(name "~"
						(effects
							(font
								(size 1.27 1.27)
							)
						)
					)
					(number "71"
						(effects
							(font
								(size 1.27 1.27)
							)
						)
					)
				)
				(pin passive line
					(at 0 -91.44 0)
					(length 3.81)
					(name "~"
						(effects
							(font
								(size 1.27 1.27)
							)
						)
					)
					(number "73"
						(effects
							(font
								(size 1.27 1.27)
							)
						)
					)
				)
				(pin passive line
					(at 0 -93.98 0)
					(length 3.81)
					(name "~"
						(effects
							(font
								(size 1.27 1.27)
							)
						)
					)
					(number "75"
						(effects
							(font
								(size 1.27 1.27)
							)
						)
					)
				)
				(pin passive line
					(at 0 -96.52 0)
					(length 3.81)
					(name "~"
						(effects
							(font
								(size 1.27 1.27)
							)
						)
					)
					(number "77"
						(effects
							(font
								(size 1.27 1.27)
							)
						)
					)
				)
				(pin passive line
					(at 0 -99.06 0)
					(length 3.81)
					(name "~"
						(effects
							(font
								(size 1.27 1.27)
							)
						)
					)
					(number "79"
						(effects
							(font
								(size 1.27 1.27)
							)
						)
					)
				)
				(pin passive line
					(at 0 -101.6 0)
					(length 3.81)
					(name "~"
						(effects
							(font
								(size 1.27 1.27)
							)
						)
					)
					(number "81"
						(effects
							(font
								(size 1.27 1.27)
							)
						)
					)
				)
				(pin passive line
					(at 0 -104.14 0)
					(length 3.81)
					(name "~"
						(effects
							(font
								(size 1.27 1.27)
							)
						)
					)
					(number "83"
						(effects
							(font
								(size 1.27 1.27)
							)
						)
					)
				)
				(pin passive line
					(at 0 -106.68 0)
					(length 3.81)
					(name "~"
						(effects
							(font
								(size 1.27 1.27)
							)
						)
					)
					(number "85"
						(effects
							(font
								(size 1.27 1.27)
							)
						)
					)
				)
				(pin passive line
					(at 0 -109.22 0)
					(length 3.81)
					(name "~"
						(effects
							(font
								(size 1.27 1.27)
							)
						)
					)
					(number "87"
						(effects
							(font
								(size 1.27 1.27)
							)
						)
					)
				)
				(pin passive line
					(at 0 -111.76 0)
					(length 3.81)
					(name "~"
						(effects
							(font
								(size 1.27 1.27)
							)
						)
					)
					(number "89"
						(effects
							(font
								(size 1.27 1.27)
							)
						)
					)
				)
				(pin passive line
					(at 0 -114.3 0)
					(length 3.81)
					(name "~"
						(effects
							(font
								(size 1.27 1.27)
							)
						)
					)
					(number "91"
						(effects
							(font
								(size 1.27 1.27)
							)
						)
					)
				)
				(pin passive line
					(at 0 -116.84 0)
					(length 3.81)
					(name "~"
						(effects
							(font
								(size 1.27 1.27)
							)
						)
					)
					(number "93"
						(effects
							(font
								(size 1.27 1.27)
							)
						)
					)
				)
				(pin passive line
					(at 0 -119.38 0)
					(length 3.81)
					(name "~"
						(effects
							(font
								(size 1.27 1.27)
							)
						)
					)
					(number "95"
						(effects
							(font
								(size 1.27 1.27)
							)
						)
					)
				)
				(pin passive line
					(at 0 -121.92 0)
					(length 3.81)
					(name "~"
						(effects
							(font
								(size 1.27 1.27)
							)
						)
					)
					(number "97"
						(effects
							(font
								(size 1.27 1.27)
							)
						)
					)
				)
				(pin passive line
					(at 0 -124.46 0)
					(length 3.81)
					(name "~"
						(effects
							(font
								(size 1.27 1.27)
							)
						)
					)
					(number "99"
						(effects
							(font
								(size 1.27 1.27)
							)
						)
					)
				)
				(pin passive line
					(at 13.97 0 180)
					(length 3.81)
					(name "~"
						(effects
							(font
								(size 1.27 1.27)
							)
						)
					)
					(number "2"
						(effects
							(font
								(size 1.27 1.27)
							)
						)
					)
				)
				(pin passive line
					(at 13.97 -2.54 180)
					(length 3.81)
					(name "~"
						(effects
							(font
								(size 1.27 1.27)
							)
						)
					)
					(number "4"
						(effects
							(font
								(size 1.27 1.27)
							)
						)
					)
				)
				(pin passive line
					(at 13.97 -5.08 180)
					(length 3.81)
					(name "~"
						(effects
							(font
								(size 1.27 1.27)
							)
						)
					)
					(number "6"
						(effects
							(font
								(size 1.27 1.27)
							)
						)
					)
				)
				(pin passive line
					(at 13.97 -7.62 180)
					(length 3.81)
					(name "~"
						(effects
							(font
								(size 1.27 1.27)
							)
						)
					)
					(number "8"
						(effects
							(font
								(size 1.27 1.27)
							)
						)
					)
				)
				(pin passive line
					(at 13.97 -10.16 180)
					(length 3.81)
					(name "~"
						(effects
							(font
								(size 1.27 1.27)
							)
						)
					)
					(number "10"
						(effects
							(font
								(size 1.27 1.27)
							)
						)
					)
				)
				(pin passive line
					(at 13.97 -12.7 180)
					(length 3.81)
					(name "~"
						(effects
							(font
								(size 1.27 1.27)
							)
						)
					)
					(number "12"
						(effects
							(font
								(size 1.27 1.27)
							)
						)
					)
				)
				(pin passive line
					(at 13.97 -15.24 180)
					(length 3.81)
					(name "~"
						(effects
							(font
								(size 1.27 1.27)
							)
						)
					)
					(number "14"
						(effects
							(font
								(size 1.27 1.27)
							)
						)
					)
				)
				(pin passive line
					(at 13.97 -17.78 180)
					(length 3.81)
					(name "~"
						(effects
							(font
								(size 1.27 1.27)
							)
						)
					)
					(number "16"
						(effects
							(font
								(size 1.27 1.27)
							)
						)
					)
				)
				(pin passive line
					(at 13.97 -20.32 180)
					(length 3.81)
					(name "~"
						(effects
							(font
								(size 1.27 1.27)
							)
						)
					)
					(number "18"
						(effects
							(font
								(size 1.27 1.27)
							)
						)
					)
				)
				(pin passive line
					(at 13.97 -22.86 180)
					(length 3.81)
					(name "~"
						(effects
							(font
								(size 1.27 1.27)
							)
						)
					)
					(number "20"
						(effects
							(font
								(size 1.27 1.27)
							)
						)
					)
				)
				(pin passive line
					(at 13.97 -25.4 180)
					(length 3.81)
					(name "~"
						(effects
							(font
								(size 1.27 1.27)
							)
						)
					)
					(number "22"
						(effects
							(font
								(size 1.27 1.27)
							)
						)
					)
				)
				(pin passive line
					(at 13.97 -27.94 180)
					(length 3.81)
					(name "~"
						(effects
							(font
								(size 1.27 1.27)
							)
						)
					)
					(number "24"
						(effects
							(font
								(size 1.27 1.27)
							)
						)
					)
				)
				(pin passive line
					(at 13.97 -30.48 180)
					(length 3.81)
					(name "~"
						(effects
							(font
								(size 1.27 1.27)
							)
						)
					)
					(number "26"
						(effects
							(font
								(size 1.27 1.27)
							)
						)
					)
				)
				(pin passive line
					(at 13.97 -33.02 180)
					(length 3.81)
					(name "~"
						(effects
							(font
								(size 1.27 1.27)
							)
						)
					)
					(number "28"
						(effects
							(font
								(size 1.27 1.27)
							)
						)
					)
				)
				(pin passive line
					(at 13.97 -35.56 180)
					(length 3.81)
					(name "~"
						(effects
							(font
								(size 1.27 1.27)
							)
						)
					)
					(number "30"
						(effects
							(font
								(size 1.27 1.27)
							)
						)
					)
				)
				(pin passive line
					(at 13.97 -38.1 180)
					(length 3.81)
					(name "~"
						(effects
							(font
								(size 1.27 1.27)
							)
						)
					)
					(number "32"
						(effects
							(font
								(size 1.27 1.27)
							)
						)
					)
				)
				(pin passive line
					(at 13.97 -40.64 180)
					(length 3.81)
					(name "~"
						(effects
							(font
								(size 1.27 1.27)
							)
						)
					)
					(number "34"
						(effects
							(font
								(size 1.27 1.27)
							)
						)
					)
				)
				(pin passive line
					(at 13.97 -43.18 180)
					(length 3.81)
					(name "~"
						(effects
							(font
								(size 1.27 1.27)
							)
						)
					)
					(number "36"
						(effects
							(font
								(size 1.27 1.27)
							)
						)
					)
				)
				(pin passive line
					(at 13.97 -45.72 180)
					(length 3.81)
					(name "~"
						(effects
							(font
								(size 1.27 1.27)
							)
						)
					)
					(number "38"
						(effects
							(font
								(size 1.27 1.27)
							)
						)
					)
				)
				(pin passive line
					(at 13.97 -48.26 180)
					(length 3.81)
					(name "~"
						(effects
							(font
								(size 1.27 1.27)
							)
						)
					)
					(number "40"
						(effects
							(font
								(size 1.27 1.27)
							)
						)
					)
				)
				(pin passive line
					(at 13.97 -50.8 180)
					(length 3.81)
					(name "~"
						(effects
							(font
								(size 1.27 1.27)
							)
						)
					)
					(number "42"
						(effects
							(font
								(size 1.27 1.27)
							)
						)
					)
				)
				(pin passive line
					(at 13.97 -53.34 180)
					(length 3.81)
					(name "~"
						(effects
							(font
								(size 1.27 1.27)
							)
						)
					)
					(number "44"
						(effects
							(font
								(size 1.27 1.27)
							)
						)
					)
				)
				(pin passive line
					(at 13.97 -55.88 180)
					(length 3.81)
					(name "~"
						(effects
							(font
								(size 1.27 1.27)
							)
						)
					)
					(number "46"
						(effects
							(font
								(size 1.27 1.27)
							)
						)
					)
				)
				(pin passive line
					(at 13.97 -58.42 180)
					(length 3.81)
					(name "~"
						(effects
							(font
								(size 1.27 1.27)
							)
						)
					)
					(number "48"
						(effects
							(font
								(size 1.27 1.27)
							)
						)
					)
				)
				(pin passive line
					(at 13.97 -60.96 180)
					(length 3.81)
					(name "~"
						(effects
							(font
								(size 1.27 1.27)
							)
						)
					)
					(number "50"
						(effects
							(font
								(size 1.27 1.27)
							)
						)
					)
				)
				(pin passive line
					(at 13.97 -63.5 180)
					(length 3.81)
					(name "~"
						(effects
							(font
								(size 1.27 1.27)
							)
						)
					)
					(number "52"
						(effects
							(font
								(size 1.27 1.27)
							)
						)
					)
				)
				(pin passive line
					(at 13.97 -66.04 180)
					(length 3.81)
					(name "~"
						(effects
							(font
								(size 1.27 1.27)
							)
						)
					)
					(number "54"
						(effects
							(font
								(size 1.27 1.27)
							)
						)
					)
				)
				(pin passive line
					(at 13.97 -68.58 180)
					(length 3.81)
					(name "~"
						(effects
							(font
								(size 1.27 1.27)
							)
						)
					)
					(number "56"
						(effects
							(font
								(size 1.27 1.27)
							)
						)
					)
				)
				(pin passive line
					(at 13.97 -71.12 180)
					(length 3.81)
					(name "~"
						(effects
							(font
								(size 1.27 1.27)
							)
						)
					)
					(number "58"
						(effects
							(font
								(size 1.27 1.27)
							)
						)
					)
				)
				(pin passive line
					(at 13.97 -73.66 180)
					(length 3.81)
					(name "~"
						(effects
							(font
								(size 1.27 1.27)
							)
						)
					)
					(number "60"
						(effects
							(font
								(size 1.27 1.27)
							)
						)
					)
				)
				(pin passive line
					(at 13.97 -76.2 180)
					(length 3.81)
					(name "~"
						(effects
							(font
								(size 1.27 1.27)
							)
						)
					)
					(number "62"
						(effects
							(font
								(size 1.27 1.27)
							)
						)
					)
				)
				(pin passive line
					(at 13.97 -78.74 180)
					(length 3.81)
					(name "~"
						(effects
							(font
								(size 1.27 1.27)
							)
						)
					)
					(number "64"
						(effects
							(font
								(size 1.27 1.27)
							)
						)
					)
				)
				(pin passive line
					(at 13.97 -81.28 180)
					(length 3.81)
					(name "~"
						(effects
							(font
								(size 1.27 1.27)
							)
						)
					)
					(number "66"
						(effects
							(font
								(size 1.27 1.27)
							)
						)
					)
				)
				(pin passive line
					(at 13.97 -83.82 180)
					(length 3.81)
					(name "~"
						(effects
							(font
								(size 1.27 1.27)
							)
						)
					)
					(number "68"
						(effects
							(font
								(size 1.27 1.27)
							)
						)
					)
				)
				(pin passive line
					(at 13.97 -86.36 180)
					(length 3.81)
					(name "~"
						(effects
							(font
								(size 1.27 1.27)
							)
						)
					)
					(number "70"
						(effects
							(font
								(size 1.27 1.27)
							)
						)
					)
				)
				(pin passive line
					(at 13.97 -88.9 180)
					(length 3.81)
					(name "~"
						(effects
							(font
								(size 1.27 1.27)
							)
						)
					)
					(number "72"
						(effects
							(font
								(size 1.27 1.27)
							)
						)
					)
				)
				(pin passive line
					(at 13.97 -91.44 180)
					(length 3.81)
					(name "~"
						(effects
							(font
								(size 1.27 1.27)
							)
						)
					)
					(number "74"
						(effects
							(font
								(size 1.27 1.27)
							)
						)
					)
				)
				(pin passive line
					(at 13.97 -93.98 180)
					(length 3.81)
					(name "~"
						(effects
							(font
								(size 1.27 1.27)
							)
						)
					)
					(number "76"
						(effects
							(font
								(size 1.27 1.27)
							)
						)
					)
				)
				(pin passive line
					(at 13.97 -96.52 180)
					(length 3.81)
					(name "~"
						(effects
							(font
								(size 1.27 1.27)
							)
						)
					)
					(number "78"
						(effects
							(font
								(size 1.27 1.27)
							)
						)
					)
				)
				(pin passive line
					(at 13.97 -99.06 180)
					(length 3.81)
					(name "~"
						(effects
							(font
								(size 1.27 1.27)
							)
						)
					)
					(number "80"
						(effects
							(font
								(size 1.27 1.27)
							)
						)
					)
				)
				(pin passive line
					(at 13.97 -101.6 180)
					(length 3.81)
					(name "~"
						(effects
							(font
								(size 1.27 1.27)
							)
						)
					)
					(number "82"
						(effects
							(font
								(size 1.27 1.27)
							)
						)
					)
				)
				(pin passive line
					(at 13.97 -104.14 180)
					(length 3.81)
					(name "~"
						(effects
							(font
								(size 1.27 1.27)
							)
						)
					)
					(number "84"
						(effects
							(font
								(size 1.27 1.27)
							)
						)
					)
				)
				(pin passive line
					(at 13.97 -106.68 180)
					(length 3.81)
					(name "~"
						(effects
							(font
								(size 1.27 1.27)
							)
						)
					)
					(number "86"
						(effects
							(font
								(size 1.27 1.27)
							)
						)
					)
				)
				(pin passive line
					(at 13.97 -109.22 180)
					(length 3.81)
					(name "~"
						(effects
							(font
								(size 1.27 1.27)
							)
						)
					)
					(number "88"
						(effects
							(font
								(size 1.27 1.27)
							)
						)
					)
				)
				(pin passive line
					(at 13.97 -111.76 180)
					(length 3.81)
					(name "~"
						(effects
							(font
								(size 1.27 1.27)
							)
						)
					)
					(number "90"
						(effects
							(font
								(size 1.27 1.27)
							)
						)
					)
				)
				(pin passive line
					(at 13.97 -114.3 180)
					(length 3.81)
					(name "~"
						(effects
							(font
								(size 1.27 1.27)
							)
						)
					)
					(number "92"
						(effects
							(font
								(size 1.27 1.27)
							)
						)
					)
				)
				(pin passive line
					(at 13.97 -116.84 180)
					(length 3.81)
					(name "~"
						(effects
							(font
								(size 1.27 1.27)
							)
						)
					)
					(number "94"
						(effects
							(font
								(size 1.27 1.27)
							)
						)
					)
				)
				(pin passive line
					(at 13.97 -119.38 180)
					(length 3.81)
					(name "~"
						(effects
							(font
								(size 1.27 1.27)
							)
						)
					)
					(number "96"
						(effects
							(font
								(size 1.27 1.27)
							)
						)
					)
				)
				(pin passive line
					(at 13.97 -121.92 180)
					(length 3.81)
					(name "~"
						(effects
							(font
								(size 1.27 1.27)
							)
						)
					)
					(number "98"
						(effects
							(font
								(size 1.27 1.27)
							)
						)
					)
				)
				(pin passive line
					(at 13.97 -124.46 180)
					(length 3.81)
					(name "~"
						(effects
							(font
								(size 1.27 1.27)
							)
						)
					)
					(number "100"
						(effects
							(font
								(size 1.27 1.27)
							)
						)
					)
				)
			)
		)
	(symbol "antmicroB2BConnectors:Socket_Molex_SlimStack_2x20_543630489"
			(exclude_from_sim no)
			(in_bom yes)
			(on_board yes)
			(property "Reference" "J"
				(at 25.4 0 0)
				(effects
					(font
						(size 1.27 1.27)
						(thickness 0.15)
					)
					(justify left bottom)
				)
			)
			(property "Value" "Socket_Molex_SlimStack_2x20_543630489"
				(at 25.4 -5.08 0)
				(effects
					(font
						(size 1.27 1.27)
						(thickness 0.15)
					)
					(justify left bottom)
					(hide yes)
				)
			)
			(property "Footprint" "antmicro-footprints:Conn_Socket_Molex_SlimStack_2x20_543630489"
				(at 25.4 -7.62 0)
				(effects
					(font
						(size 1.27 1.27)
						(thickness 0.15)
					)
					(justify left bottom)
					(hide yes)
				)
			)
			(property "Datasheet" "https://www.molex.com/pdm_docs/sd/543630489_sd.pdf"
				(at 25.4 -10.16 0)
				(effects
					(font
						(size 1.27 1.27)
						(thickness 0.15)
					)
					(justify left bottom)
					(hide yes)
				)
			)
			(property "Description" "Mezzanine Connector, 2mm Height, Receptacle, 0.5 mm, 2 Rows, 40 Contacts, Surface Mount"
				(at 0 0 0)
				(effects
					(font
						(size 1.27 1.27)
					)
					(hide yes)
				)
			)
			(property "MPN" "543630489"
				(at 25.4 -2.54 0)
				(effects
					(font
						(size 1.27 1.27)
						(thickness 0.15)
					)
					(justify left bottom)
				)
			)
			(property "Manufacturer" "Molex"
				(at 25.4 -15.24 0)
				(effects
					(font
						(size 1.27 1.27)
						(thickness 0.15)
					)
					(justify left bottom)
					(hide yes)
				)
			)
			(property "Pitch" "0.5 mm"
				(at 25.4 -12.7 0)
				(effects
					(font
						(size 1.27 1.27)
						(thickness 0.15)
					)
					(justify left bottom)
					(hide yes)
				)
			)
			(property "Author" "Antmicro"
				(at 25.4 -17.78 0)
				(effects
					(font
						(size 1.27 1.27)
						(thickness 0.15)
					)
					(justify left bottom)
					(hide yes)
				)
			)
			(property "License" "Apache-2.0"
				(at 25.4 -20.32 0)
				(effects
					(font
						(size 1.27 1.27)
						(thickness 0.15)
					)
					(justify left bottom)
					(hide yes)
				)
			)
			(property "ki_keywords" "CONNECTOR, B2B, SOCKET"
				(at 0 0 0)
				(effects
					(font
						(size 1.27 1.27)
					)
					(hide yes)
				)
			)
			(symbol "Socket_Molex_SlimStack_2x20_543630489_1_1"
				(rectangle
					(start 2.54 2.54)
					(end 8.89 -52.705)
					(stroke
						(width 0.254)
						(type default)
					)
					(fill
						(type background)
					)
				)
				(rectangle
					(start 3.81 1.27)
					(end 7.62 -51.435)
					(stroke
						(width 0.254)
						(type default)
					)
					(fill
						(type background)
					)
				)
				(pin passive line
					(at 0 0 0)
					(length 2.54)
					(name "~"
						(effects
							(font
								(size 1.27 1.27)
							)
						)
					)
					(number "1"
						(effects
							(font
								(size 1.27 1.27)
							)
						)
					)
				)
				(pin passive line
					(at 0 -2.54 0)
					(length 2.54)
					(name "~"
						(effects
							(font
								(size 1.27 1.27)
							)
						)
					)
					(number "3"
						(effects
							(font
								(size 1.27 1.27)
							)
						)
					)
				)
				(pin passive line
					(at 0 -5.08 0)
					(length 2.54)
					(name "~"
						(effects
							(font
								(size 1.27 1.27)
							)
						)
					)
					(number "5"
						(effects
							(font
								(size 1.27 1.27)
							)
						)
					)
				)
				(pin passive line
					(at 0 -7.62 0)
					(length 2.54)
					(name "~"
						(effects
							(font
								(size 1.27 1.27)
							)
						)
					)
					(number "7"
						(effects
							(font
								(size 1.27 1.27)
							)
						)
					)
				)
				(pin passive line
					(at 0 -10.16 0)
					(length 2.54)
					(name "~"
						(effects
							(font
								(size 1.27 1.27)
							)
						)
					)
					(number "9"
						(effects
							(font
								(size 1.27 1.27)
							)
						)
					)
				)
				(pin passive line
					(at 0 -12.7 0)
					(length 2.54)
					(name "~"
						(effects
							(font
								(size 1.27 1.27)
							)
						)
					)
					(number "11"
						(effects
							(font
								(size 1.27 1.27)
							)
						)
					)
				)
				(pin passive line
					(at 0 -15.24 0)
					(length 2.54)
					(name "~"
						(effects
							(font
								(size 1.27 1.27)
							)
						)
					)
					(number "13"
						(effects
							(font
								(size 1.27 1.27)
							)
						)
					)
				)
				(pin passive line
					(at 0 -17.78 0)
					(length 2.54)
					(name "~"
						(effects
							(font
								(size 1.27 1.27)
							)
						)
					)
					(number "15"
						(effects
							(font
								(size 1.27 1.27)
							)
						)
					)
				)
				(pin passive line
					(at 0 -20.32 0)
					(length 2.54)
					(name "~"
						(effects
							(font
								(size 1.27 1.27)
							)
						)
					)
					(number "17"
						(effects
							(font
								(size 1.27 1.27)
							)
						)
					)
				)
				(pin passive line
					(at 0 -22.86 0)
					(length 2.54)
					(name "~"
						(effects
							(font
								(size 1.27 1.27)
							)
						)
					)
					(number "19"
						(effects
							(font
								(size 1.27 1.27)
							)
						)
					)
				)
				(pin passive line
					(at 0 -25.4 0)
					(length 2.54)
					(name "~"
						(effects
							(font
								(size 1.27 1.27)
							)
						)
					)
					(number "21"
						(effects
							(font
								(size 1.27 1.27)
							)
						)
					)
				)
				(pin passive line
					(at 0 -27.94 0)
					(length 2.54)
					(name "~"
						(effects
							(font
								(size 1.27 1.27)
							)
						)
					)
					(number "23"
						(effects
							(font
								(size 1.27 1.27)
							)
						)
					)
				)
				(pin passive line
					(at 0 -30.48 0)
					(length 2.54)
					(name "~"
						(effects
							(font
								(size 1.27 1.27)
							)
						)
					)
					(number "25"
						(effects
							(font
								(size 1.27 1.27)
							)
						)
					)
				)
				(pin passive line
					(at 0 -33.02 0)
					(length 2.54)
					(name "~"
						(effects
							(font
								(size 1.27 1.27)
							)
						)
					)
					(number "27"
						(effects
							(font
								(size 1.27 1.27)
							)
						)
					)
				)
				(pin passive line
					(at 0 -35.56 0)
					(length 2.54)
					(name "~"
						(effects
							(font
								(size 1.27 1.27)
							)
						)
					)
					(number "29"
						(effects
							(font
								(size 1.27 1.27)
							)
						)
					)
				)
				(pin passive line
					(at 0 -38.1 0)
					(length 2.54)
					(name "~"
						(effects
							(font
								(size 1.27 1.27)
							)
						)
					)
					(number "31"
						(effects
							(font
								(size 1.27 1.27)
							)
						)
					)
				)
				(pin passive line
					(at 0 -40.64 0)
					(length 2.54)
					(name "~"
						(effects
							(font
								(size 1.27 1.27)
							)
						)
					)
					(number "33"
						(effects
							(font
								(size 1.27 1.27)
							)
						)
					)
				)
				(pin passive line
					(at 0 -43.18 0)
					(length 2.54)
					(name "~"
						(effects
							(font
								(size 1.27 1.27)
							)
						)
					)
					(number "35"
						(effects
							(font
								(size 1.27 1.27)
							)
						)
					)
				)
				(pin passive line
					(at 0 -45.72 0)
					(length 2.54)
					(name "~"
						(effects
							(font
								(size 1.27 1.27)
							)
						)
					)
					(number "37"
						(effects
							(font
								(size 1.27 1.27)
							)
						)
					)
				)
				(pin passive line
					(at 0 -48.26 0)
					(length 2.54)
					(name "~"
						(effects
							(font
								(size 1.27 1.27)
							)
						)
					)
					(number "39"
						(effects
							(font
								(size 1.27 1.27)
							)
						)
					)
				)
				(pin passive line
					(at 11.43 0 180)
					(length 2.54)
					(name "~"
						(effects
							(font
								(size 1.27 1.27)
							)
						)
					)
					(number "2"
						(effects
							(font
								(size 1.27 1.27)
							)
						)
					)
				)
				(pin passive line
					(at 11.43 -2.54 180)
					(length 2.54)
					(name "~"
						(effects
							(font
								(size 1.27 1.27)
							)
						)
					)
					(number "4"
						(effects
							(font
								(size 1.27 1.27)
							)
						)
					)
				)
				(pin passive line
					(at 11.43 -5.08 180)
					(length 2.54)
					(name "~"
						(effects
							(font
								(size 1.27 1.27)
							)
						)
					)
					(number "6"
						(effects
							(font
								(size 1.27 1.27)
							)
						)
					)
				)
				(pin passive line
					(at 11.43 -7.62 180)
					(length 2.54)
					(name "~"
						(effects
							(font
								(size 1.27 1.27)
							)
						)
					)
					(number "8"
						(effects
							(font
								(size 1.27 1.27)
							)
						)
					)
				)
				(pin passive line
					(at 11.43 -10.16 180)
					(length 2.54)
					(name "~"
						(effects
							(font
								(size 1.27 1.27)
							)
						)
					)
					(number "10"
						(effects
							(font
								(size 1.27 1.27)
							)
						)
					)
				)
				(pin passive line
					(at 11.43 -12.7 180)
					(length 2.54)
					(name "~"
						(effects
							(font
								(size 1.27 1.27)
							)
						)
					)
					(number "12"
						(effects
							(font
								(size 1.27 1.27)
							)
						)
					)
				)
				(pin passive line
					(at 11.43 -15.24 180)
					(length 2.54)
					(name "~"
						(effects
							(font
								(size 1.27 1.27)
							)
						)
					)
					(number "14"
						(effects
							(font
								(size 1.27 1.27)
							)
						)
					)
				)
				(pin passive line
					(at 11.43 -17.78 180)
					(length 2.54)
					(name "~"
						(effects
							(font
								(size 1.27 1.27)
							)
						)
					)
					(number "16"
						(effects
							(font
								(size 1.27 1.27)
							)
						)
					)
				)
				(pin passive line
					(at 11.43 -20.32 180)
					(length 2.54)
					(name "~"
						(effects
							(font
								(size 1.27 1.27)
							)
						)
					)
					(number "18"
						(effects
							(font
								(size 1.27 1.27)
							)
						)
					)
				)
				(pin passive line
					(at 11.43 -22.86 180)
					(length 2.54)
					(name "~"
						(effects
							(font
								(size 1.27 1.27)
							)
						)
					)
					(number "20"
						(effects
							(font
								(size 1.27 1.27)
							)
						)
					)
				)
				(pin passive line
					(at 11.43 -25.4 180)
					(length 2.54)
					(name "~"
						(effects
							(font
								(size 1.27 1.27)
							)
						)
					)
					(number "22"
						(effects
							(font
								(size 1.27 1.27)
							)
						)
					)
				)
				(pin passive line
					(at 11.43 -27.94 180)
					(length 2.54)
					(name "~"
						(effects
							(font
								(size 1.27 1.27)
							)
						)
					)
					(number "24"
						(effects
							(font
								(size 1.27 1.27)
							)
						)
					)
				)
				(pin passive line
					(at 11.43 -30.48 180)
					(length 2.54)
					(name "~"
						(effects
							(font
								(size 1.27 1.27)
							)
						)
					)
					(number "26"
						(effects
							(font
								(size 1.27 1.27)
							)
						)
					)
				)
				(pin passive line
					(at 11.43 -33.02 180)
					(length 2.54)
					(name "~"
						(effects
							(font
								(size 1.27 1.27)
							)
						)
					)
					(number "28"
						(effects
							(font
								(size 1.27 1.27)
							)
						)
					)
				)
				(pin passive line
					(at 11.43 -35.56 180)
					(length 2.54)
					(name "~"
						(effects
							(font
								(size 1.27 1.27)
							)
						)
					)
					(number "30"
						(effects
							(font
								(size 1.27 1.27)
							)
						)
					)
				)
				(pin passive line
					(at 11.43 -38.1 180)
					(length 2.54)
					(name "~"
						(effects
							(font
								(size 1.27 1.27)
							)
						)
					)
					(number "32"
						(effects
							(font
								(size 1.27 1.27)
							)
						)
					)
				)
				(pin passive line
					(at 11.43 -40.64 180)
					(length 2.54)
					(name "~"
						(effects
							(font
								(size 1.27 1.27)
							)
						)
					)
					(number "34"
						(effects
							(font
								(size 1.27 1.27)
							)
						)
					)
				)
				(pin passive line
					(at 11.43 -43.18 180)
					(length 2.54)
					(name "~"
						(effects
							(font
								(size 1.27 1.27)
							)
						)
					)
					(number "36"
						(effects
							(font
								(size 1.27 1.27)
							)
						)
					)
				)
				(pin passive line
					(at 11.43 -45.72 180)
					(length 2.54)
					(name "~"
						(effects
							(font
								(size 1.27 1.27)
							)
						)
					)
					(number "38"
						(effects
							(font
								(size 1.27 1.27)
							)
						)
					)
				)
				(pin passive line
					(at 11.43 -48.26 180)
					(length 2.54)
					(name "~"
						(effects
							(font
								(size 1.27 1.27)
							)
						)
					)
					(number "40"
						(effects
							(font
								(size 1.27 1.27)
							)
						)
					)
				)
				(pin passive line
					(at 11.43 -50.8 180)
					(length 2.54)
					(name "~"
						(effects
							(font
								(size 1.27 1.27)
							)
						)
					)
					(number "MP"
						(effects
							(font
								(size 1.27 1.27)
							)
						)
					)
				)
			)
		)
	(symbol "antmicroB2BConnectors:Socket_Samtec_ERF5_2x20_ERF5-020-05.0-L-DV-K-TR"
			(exclude_from_sim no)
			(in_bom yes)
			(on_board yes)
			(property "Reference" "J"
				(at 26.67 0 0)
				(effects
					(font
						(size 1.27 1.27)
						(thickness 0.15)
					)
					(justify left bottom)
				)
			)
			(property "Value" "Socket_Samtec_ERF5_2x20_ERF5-020-05.0-L-DV-K-TR"
				(at 26.67 -5.08 0)
				(effects
					(font
						(size 1.27 1.27)
						(thickness 0.15)
					)
					(justify left bottom)
					(hide yes)
				)
			)
			(property "Footprint" "antmicro-footprints:Conn_Socket_Samtec_ERF5_2x20_ERF5-020-05.0-L-DV-K-TR"
				(at 26.67 -7.62 0)
				(effects
					(font
						(size 1.27 1.27)
						(thickness 0.15)
					)
					(justify left bottom)
					(hide yes)
				)
			)
			(property "Datasheet" "https://suddendocs.samtec.com/productspecs/erm5-erf5.pdf?_gl=1*1g914su*_ga*MTE0MzExNjY4MC4xNjcyMTQ5NTUz*_ga_3KFNZC07WW*MTY3Mjg0NzY5Ny42LjEuMTY3Mjg0ODE3MS42MC4wLjA."
				(at 26.67 -10.16 0)
				(effects
					(font
						(size 1.27 1.27)
						(thickness 0.15)
					)
					(justify left bottom)
					(hide yes)
				)
			)
			(property "Description" "Board to Board & Mezzanine Connectors 0.50 mm Edge Rate Rugged High Speed Socket"
				(at 0 0 0)
				(effects
					(font
						(size 1.27 1.27)
					)
					(hide yes)
				)
			)
			(property "MPN" "ERF5-020-05.0-L-DV-K-TR"
				(at 26.67 -2.54 0)
				(effects
					(font
						(size 1.27 1.27)
						(thickness 0.15)
					)
					(justify left bottom)
				)
			)
			(property "Manufacturer" "Samtec"
				(at 26.67 -12.7 0)
				(effects
					(font
						(size 1.27 1.27)
						(thickness 0.15)
					)
					(justify left bottom)
					(hide yes)
				)
			)
			(property "Author" "Antmicro"
				(at 26.67 -17.78 0)
				(effects
					(font
						(size 1.27 1.27)
						(thickness 0.15)
					)
					(justify left bottom)
					(hide yes)
				)
			)
			(property "License" "Apache-2.0"
				(at 26.67 -20.32 0)
				(effects
					(font
						(size 1.27 1.27)
						(thickness 0.15)
					)
					(justify left bottom)
					(hide yes)
				)
			)
			(property "Pitch" "0.5 mm"
				(at 26.67 -15.24 0)
				(effects
					(font
						(size 1.27 1.27)
					)
					(justify left bottom)
					(hide yes)
				)
			)
			(property "ki_keywords" "CONNECTOR, B2B, SOCKET"
				(at 0 0 0)
				(effects
					(font
						(size 1.27 1.27)
					)
					(hide yes)
				)
			)
			(symbol "Socket_Samtec_ERF5_2x20_ERF5-020-05.0-L-DV-K-TR_1_1"
				(rectangle
					(start 2.54 2.54)
					(end 8.89 -50.8)
					(stroke
						(width 0.254)
						(type default)
					)
					(fill
						(type background)
					)
				)
				(rectangle
					(start 3.81 1.27)
					(end 7.62 -49.53)
					(stroke
						(width 0.254)
						(type default)
					)
					(fill
						(type background)
					)
				)
				(pin passive line
					(at 0 0 0)
					(length 2.54)
					(name "~"
						(effects
							(font
								(size 1.27 1.27)
							)
						)
					)
					(number "1"
						(effects
							(font
								(size 1.27 1.27)
							)
						)
					)
				)
				(pin passive line
					(at 0 -2.54 0)
					(length 2.54)
					(name "~"
						(effects
							(font
								(size 1.27 1.27)
							)
						)
					)
					(number "3"
						(effects
							(font
								(size 1.27 1.27)
							)
						)
					)
				)
				(pin passive line
					(at 0 -5.08 0)
					(length 2.54)
					(name "~"
						(effects
							(font
								(size 1.27 1.27)
							)
						)
					)
					(number "5"
						(effects
							(font
								(size 1.27 1.27)
							)
						)
					)
				)
				(pin passive line
					(at 0 -7.62 0)
					(length 2.54)
					(name "~"
						(effects
							(font
								(size 1.27 1.27)
							)
						)
					)
					(number "7"
						(effects
							(font
								(size 1.27 1.27)
							)
						)
					)
				)
				(pin passive line
					(at 0 -10.16 0)
					(length 2.54)
					(name "~"
						(effects
							(font
								(size 1.27 1.27)
							)
						)
					)
					(number "9"
						(effects
							(font
								(size 1.27 1.27)
							)
						)
					)
				)
				(pin passive line
					(at 0 -12.7 0)
					(length 2.54)
					(name "~"
						(effects
							(font
								(size 1.27 1.27)
							)
						)
					)
					(number "11"
						(effects
							(font
								(size 1.27 1.27)
							)
						)
					)
				)
				(pin passive line
					(at 0 -15.24 0)
					(length 2.54)
					(name "~"
						(effects
							(font
								(size 1.27 1.27)
							)
						)
					)
					(number "13"
						(effects
							(font
								(size 1.27 1.27)
							)
						)
					)
				)
				(pin passive line
					(at 0 -17.78 0)
					(length 2.54)
					(name "~"
						(effects
							(font
								(size 1.27 1.27)
							)
						)
					)
					(number "15"
						(effects
							(font
								(size 1.27 1.27)
							)
						)
					)
				)
				(pin passive line
					(at 0 -20.32 0)
					(length 2.54)
					(name "~"
						(effects
							(font
								(size 1.27 1.27)
							)
						)
					)
					(number "17"
						(effects
							(font
								(size 1.27 1.27)
							)
						)
					)
				)
				(pin passive line
					(at 0 -22.86 0)
					(length 2.54)
					(name "~"
						(effects
							(font
								(size 1.27 1.27)
							)
						)
					)
					(number "19"
						(effects
							(font
								(size 1.27 1.27)
							)
						)
					)
				)
				(pin passive line
					(at 0 -25.4 0)
					(length 2.54)
					(name "~"
						(effects
							(font
								(size 1.27 1.27)
							)
						)
					)
					(number "21"
						(effects
							(font
								(size 1.27 1.27)
							)
						)
					)
				)
				(pin passive line
					(at 0 -27.94 0)
					(length 2.54)
					(name "~"
						(effects
							(font
								(size 1.27 1.27)
							)
						)
					)
					(number "23"
						(effects
							(font
								(size 1.27 1.27)
							)
						)
					)
				)
				(pin passive line
					(at 0 -30.48 0)
					(length 2.54)
					(name "~"
						(effects
							(font
								(size 1.27 1.27)
							)
						)
					)
					(number "25"
						(effects
							(font
								(size 1.27 1.27)
							)
						)
					)
				)
				(pin passive line
					(at 0 -33.02 0)
					(length 2.54)
					(name "~"
						(effects
							(font
								(size 1.27 1.27)
							)
						)
					)
					(number "27"
						(effects
							(font
								(size 1.27 1.27)
							)
						)
					)
				)
				(pin passive line
					(at 0 -35.56 0)
					(length 2.54)
					(name "~"
						(effects
							(font
								(size 1.27 1.27)
							)
						)
					)
					(number "29"
						(effects
							(font
								(size 1.27 1.27)
							)
						)
					)
				)
				(pin passive line
					(at 0 -38.1 0)
					(length 2.54)
					(name "~"
						(effects
							(font
								(size 1.27 1.27)
							)
						)
					)
					(number "31"
						(effects
							(font
								(size 1.27 1.27)
							)
						)
					)
				)
				(pin passive line
					(at 0 -40.64 0)
					(length 2.54)
					(name "~"
						(effects
							(font
								(size 1.27 1.27)
							)
						)
					)
					(number "33"
						(effects
							(font
								(size 1.27 1.27)
							)
						)
					)
				)
				(pin passive line
					(at 0 -43.18 0)
					(length 2.54)
					(name "~"
						(effects
							(font
								(size 1.27 1.27)
							)
						)
					)
					(number "35"
						(effects
							(font
								(size 1.27 1.27)
							)
						)
					)
				)
				(pin passive line
					(at 0 -45.72 0)
					(length 2.54)
					(name "~"
						(effects
							(font
								(size 1.27 1.27)
							)
						)
					)
					(number "37"
						(effects
							(font
								(size 1.27 1.27)
							)
						)
					)
				)
				(pin passive line
					(at 0 -48.26 0)
					(length 2.54)
					(name "~"
						(effects
							(font
								(size 1.27 1.27)
							)
						)
					)
					(number "39"
						(effects
							(font
								(size 1.27 1.27)
							)
						)
					)
				)
				(pin passive line
					(at 11.43 0 180)
					(length 2.54)
					(name "~"
						(effects
							(font
								(size 1.27 1.27)
							)
						)
					)
					(number "2"
						(effects
							(font
								(size 1.27 1.27)
							)
						)
					)
				)
				(pin passive line
					(at 11.43 -2.54 180)
					(length 2.54)
					(name "~"
						(effects
							(font
								(size 1.27 1.27)
							)
						)
					)
					(number "4"
						(effects
							(font
								(size 1.27 1.27)
							)
						)
					)
				)
				(pin passive line
					(at 11.43 -5.08 180)
					(length 2.54)
					(name "~"
						(effects
							(font
								(size 1.27 1.27)
							)
						)
					)
					(number "6"
						(effects
							(font
								(size 1.27 1.27)
							)
						)
					)
				)
				(pin passive line
					(at 11.43 -7.62 180)
					(length 2.54)
					(name "~"
						(effects
							(font
								(size 1.27 1.27)
							)
						)
					)
					(number "8"
						(effects
							(font
								(size 1.27 1.27)
							)
						)
					)
				)
				(pin passive line
					(at 11.43 -10.16 180)
					(length 2.54)
					(name "~"
						(effects
							(font
								(size 1.27 1.27)
							)
						)
					)
					(number "10"
						(effects
							(font
								(size 1.27 1.27)
							)
						)
					)
				)
				(pin passive line
					(at 11.43 -12.7 180)
					(length 2.54)
					(name "~"
						(effects
							(font
								(size 1.27 1.27)
							)
						)
					)
					(number "12"
						(effects
							(font
								(size 1.27 1.27)
							)
						)
					)
				)
				(pin passive line
					(at 11.43 -15.24 180)
					(length 2.54)
					(name "~"
						(effects
							(font
								(size 1.27 1.27)
							)
						)
					)
					(number "14"
						(effects
							(font
								(size 1.27 1.27)
							)
						)
					)
				)
				(pin passive line
					(at 11.43 -17.78 180)
					(length 2.54)
					(name "~"
						(effects
							(font
								(size 1.27 1.27)
							)
						)
					)
					(number "16"
						(effects
							(font
								(size 1.27 1.27)
							)
						)
					)
				)
				(pin passive line
					(at 11.43 -20.32 180)
					(length 2.54)
					(name "~"
						(effects
							(font
								(size 1.27 1.27)
							)
						)
					)
					(number "18"
						(effects
							(font
								(size 1.27 1.27)
							)
						)
					)
				)
				(pin passive line
					(at 11.43 -22.86 180)
					(length 2.54)
					(name "~"
						(effects
							(font
								(size 1.27 1.27)
							)
						)
					)
					(number "20"
						(effects
							(font
								(size 1.27 1.27)
							)
						)
					)
				)
				(pin passive line
					(at 11.43 -25.4 180)
					(length 2.54)
					(name "~"
						(effects
							(font
								(size 1.27 1.27)
							)
						)
					)
					(number "22"
						(effects
							(font
								(size 1.27 1.27)
							)
						)
					)
				)
				(pin passive line
					(at 11.43 -27.94 180)
					(length 2.54)
					(name "~"
						(effects
							(font
								(size 1.27 1.27)
							)
						)
					)
					(number "24"
						(effects
							(font
								(size 1.27 1.27)
							)
						)
					)
				)
				(pin passive line
					(at 11.43 -30.48 180)
					(length 2.54)
					(name "~"
						(effects
							(font
								(size 1.27 1.27)
							)
						)
					)
					(number "26"
						(effects
							(font
								(size 1.27 1.27)
							)
						)
					)
				)
				(pin passive line
					(at 11.43 -33.02 180)
					(length 2.54)
					(name "~"
						(effects
							(font
								(size 1.27 1.27)
							)
						)
					)
					(number "28"
						(effects
							(font
								(size 1.27 1.27)
							)
						)
					)
				)
				(pin passive line
					(at 11.43 -35.56 180)
					(length 2.54)
					(name "~"
						(effects
							(font
								(size 1.27 1.27)
							)
						)
					)
					(number "30"
						(effects
							(font
								(size 1.27 1.27)
							)
						)
					)
				)
				(pin passive line
					(at 11.43 -38.1 180)
					(length 2.54)
					(name "~"
						(effects
							(font
								(size 1.27 1.27)
							)
						)
					)
					(number "32"
						(effects
							(font
								(size 1.27 1.27)
							)
						)
					)
				)
				(pin passive line
					(at 11.43 -40.64 180)
					(length 2.54)
					(name "~"
						(effects
							(font
								(size 1.27 1.27)
							)
						)
					)
					(number "34"
						(effects
							(font
								(size 1.27 1.27)
							)
						)
					)
				)
				(pin passive line
					(at 11.43 -43.18 180)
					(length 2.54)
					(name "~"
						(effects
							(font
								(size 1.27 1.27)
							)
						)
					)
					(number "36"
						(effects
							(font
								(size 1.27 1.27)
							)
						)
					)
				)
				(pin passive line
					(at 11.43 -45.72 180)
					(length 2.54)
					(name "~"
						(effects
							(font
								(size 1.27 1.27)
							)
						)
					)
					(number "38"
						(effects
							(font
								(size 1.27 1.27)
							)
						)
					)
				)
				(pin passive line
					(at 11.43 -48.26 180)
					(length 2.54)
					(name "~"
						(effects
							(font
								(size 1.27 1.27)
							)
						)
					)
					(number "40"
						(effects
							(font
								(size 1.27 1.27)
							)
						)
					)
				)
			)
		)
	(symbol "antmicroBatteryHoldersClipsContacts:Battery_Holder_MS621FE-FL11E"
			(pin_names
				(offset 0)
			)
			(exclude_from_sim no)
			(in_bom yes)
			(on_board yes)
			(property "Reference" "BT"
				(at 17.78 -2.54 0)
				(effects
					(font
						(size 1.27 1.27)
						(thickness 0.15)
					)
					(justify left bottom)
				)
			)
			(property "Value" "Battery_Holder_MS621FE-FL11E"
				(at 17.78 -7.62 0)
				(effects
					(font
						(size 1.27 1.27)
						(thickness 0.15)
					)
					(justify left bottom)
					(hide yes)
				)
			)
			(property "Footprint" "antmicro-footprints:MS621FE-FL11E"
				(at 17.78 -10.16 0)
				(effects
					(font
						(size 1.27 1.27)
						(thickness 0.15)
					)
					(justify left bottom)
					(hide yes)
				)
			)
			(property "Datasheet" "https://www.sii.co.jp/en/me/datasheets/ms-rechargeable/ms621fe/"
				(at 17.78 -12.7 0)
				(effects
					(font
						(size 1.27 1.27)
						(thickness 0.15)
					)
					(justify left bottom)
					(hide yes)
				)
			)
			(property "Description" "Rechargeable Battery, Coin Cell, Single Cell, 3 V, Lithium Manganese Dioxide, 5.5 mAh, Button Cell"
				(at 17.78 -22.86 0)
				(effects
					(font
						(size 1.27 1.27)
					)
					(justify left bottom)
					(hide yes)
				)
			)
			(property "Manufacturer" "Seiko Instruments"
				(at 17.78 -15.24 0)
				(effects
					(font
						(size 1.27 1.27)
						(thickness 0.15)
					)
					(justify left bottom)
					(hide yes)
				)
			)
			(property "MPN" "MS621FE-FL11E"
				(at 17.78 -5.08 0)
				(effects
					(font
						(size 1.27 1.27)
						(thickness 0.15)
					)
					(justify left bottom)
				)
			)
			(property "Author" "Antmicro"
				(at 17.78 -17.78 0)
				(effects
					(font
						(size 1.27 1.27)
						(thickness 0.15)
					)
					(justify left bottom)
					(hide yes)
				)
			)
			(property "License" "Apache-2.0"
				(at 17.78 -20.32 0)
				(effects
					(font
						(size 1.27 1.27)
						(thickness 0.15)
					)
					(justify left bottom)
					(hide yes)
				)
			)
			(property "ki_keywords" "HORIZONTAL, SMT, HOLDER, BATTERY"
				(at 0 0 0)
				(effects
					(font
						(size 1.27 1.27)
					)
					(hide yes)
				)
			)
			(symbol "Battery_Holder_MS621FE-FL11E_0_1"
				(rectangle
					(start -1.27 -5.08)
					(end 1.27 -4.826)
					(stroke
						(width 0.254)
						(type default)
					)
					(fill
						(type outline)
					)
				)
				(polyline
					(pts
						(xy 0 -2.54) (xy 0 -3.81)
					)
					(stroke
						(width 0.254)
						(type default)
					)
					(fill
						(type none)
					)
				)
			)
			(symbol "Battery_Holder_MS621FE-FL11E_1_1"
				(polyline
					(pts
						(xy -2.54 -3.81) (xy 2.54 -3.81)
					)
					(stroke
						(width 0.254)
						(type default)
					)
					(fill
						(type background)
					)
				)
				(polyline
					(pts
						(xy 0 -6.35) (xy 0 -5.08)
					)
					(stroke
						(width 0.254)
						(type default)
					)
					(fill
						(type background)
					)
				)
				(pin passive line
					(at 0 0 270)
					(length 2.54)
					(name "+"
						(effects
							(font
								(size 1.27 1.27)
							)
						)
					)
					(number "1"
						(effects
							(font
								(size 1.27 1.27)
							)
						)
					)
				)
				(pin passive line
					(at 0 -8.89 90)
					(length 2.54)
					(name "-"
						(effects
							(font
								(size 1.27 1.27)
							)
						)
					)
					(number "2"
						(effects
							(font
								(size 1.27 1.27)
							)
						)
					)
				)
			)
		)
	(symbol "antmicroCapacitors0402:C_100n_0402"
			(pin_numbers
				(hide yes)
			)
			(pin_names
				(hide yes)
			)
			(exclude_from_sim no)
			(in_bom yes)
			(on_board yes)
			(property "Reference" "C"
				(at 20.32 -5.08 0)
				(effects
					(font
						(size 1.27 1.27)
						(thickness 0.15)
					)
					(justify left bottom)
				)
			)
			(property "Value" "C_100n_0402"
				(at 20.32 -10.16 0)
				(effects
					(font
						(size 1.27 1.27)
						(thickness 0.15)
					)
					(justify left bottom)
					(hide yes)
				)
			)
			(property "Footprint" "antmicro-footprints:C_0402_1005Metric"
				(at 20.32 -12.7 0)
				(effects
					(font
						(size 1.27 1.27)
						(thickness 0.15)
					)
					(justify left bottom)
					(hide yes)
				)
			)
			(property "Datasheet" "https://www.murata.com/products/productdetail?partno=GRM155R61H104KE14%23"
				(at 20.32 -15.24 0)
				(effects
					(font
						(size 1.27 1.27)
						(thickness 0.15)
					)
					(justify left bottom)
					(hide yes)
				)
			)
			(property "Description" "SMD Multilayer Ceramic Capacitor, 0.1 µF, 50 V, 0402 [1005 Metric], ± 10%, X5R, GRM Series"
				(at 0 0 0)
				(effects
					(font
						(size 1.27 1.27)
					)
					(hide yes)
				)
			)
			(property "MPN" "GRM155R61H104KE14D"
				(at 20.32 -17.78 0)
				(effects
					(font
						(size 1.27 1.27)
						(thickness 0.15)
					)
					(justify left bottom)
					(hide yes)
				)
			)
			(property "Manufacturer" "Murata"
				(at 20.32 -20.32 0)
				(effects
					(font
						(size 1.27 1.27)
						(thickness 0.15)
					)
					(justify left bottom)
					(hide yes)
				)
			)
			(property "License" "Apache-2.0"
				(at 20.32 -22.86 0)
				(effects
					(font
						(size 1.27 1.27)
						(thickness 0.15)
					)
					(justify left bottom)
					(hide yes)
				)
			)
			(property "Author" "Antmicro"
				(at 20.32 -25.4 0)
				(effects
					(font
						(size 1.27 1.27)
						(thickness 0.15)
					)
					(justify left bottom)
					(hide yes)
				)
			)
			(property "Val" "100n"
				(at 20.32 -7.62 0)
				(effects
					(font
						(size 1.27 1.27)
						(thickness 0.15)
					)
					(justify left bottom)
				)
			)
			(property "Voltage" "50V"
				(at 20.32 -27.94 0)
				(effects
					(font
						(size 1.27 1.27)
					)
					(justify left bottom)
					(hide yes)
				)
			)
			(property "Dielectric" "X5R"
				(at 20.32 -30.48 0)
				(effects
					(font
						(size 1.27 1.27)
					)
					(justify left bottom)
					(hide yes)
				)
			)
			(property "ki_keywords" "0402, SMT, CAPACITOR, PASSIVE, CERAMIC, MLCC"
				(at 0 0 0)
				(effects
					(font
						(size 1.27 1.27)
					)
					(hide yes)
				)
			)
			(symbol "C_100n_0402_0_1"
				(polyline
					(pts
						(xy 2.032 -1.524) (xy 2.032 1.524)
					)
					(stroke
						(width 0.3048)
						(type default)
					)
					(fill
						(type none)
					)
				)
				(polyline
					(pts
						(xy 3.048 -1.524) (xy 3.048 1.524)
					)
					(stroke
						(width 0.3302)
						(type default)
					)
					(fill
						(type none)
					)
				)
			)
			(symbol "C_100n_0402_1_1"
				(pin passive line
					(at 0 0 0)
					(length 2.032)
					(name "~"
						(effects
							(font
								(size 1.27 1.27)
							)
						)
					)
					(number "1"
						(effects
							(font
								(size 1.27 1.27)
							)
						)
					)
				)
				(pin passive line
					(at 5.08 0 180)
					(length 2.032)
					(name "~"
						(effects
							(font
								(size 1.27 1.27)
							)
						)
					)
					(number "2"
						(effects
							(font
								(size 1.27 1.27)
							)
						)
					)
				)
			)
		)
	(symbol "antmicroCapacitors0402:C_10n_0402"
			(pin_numbers
				(hide yes)
			)
			(pin_names
				(hide yes)
			)
			(exclude_from_sim no)
			(in_bom yes)
			(on_board yes)
			(property "Reference" "C"
				(at 20.32 -5.08 0)
				(effects
					(font
						(size 1.27 1.27)
						(thickness 0.15)
					)
					(justify left bottom)
				)
			)
			(property "Value" "C_10n_0402"
				(at 20.32 -10.16 0)
				(effects
					(font
						(size 1.27 1.27)
						(thickness 0.15)
					)
					(justify left bottom)
					(hide yes)
				)
			)
			(property "Footprint" "antmicro-footprints:C_0402_1005Metric"
				(at 20.32 -12.7 0)
				(effects
					(font
						(size 1.27 1.27)
						(thickness 0.15)
					)
					(justify left bottom)
					(hide yes)
				)
			)
			(property "Datasheet" "https://www.murata.com/products/productdetail?partno=GRM155R71H103KA88%23"
				(at 20.32 -15.24 0)
				(effects
					(font
						(size 1.27 1.27)
						(thickness 0.15)
					)
					(justify left bottom)
					(hide yes)
				)
			)
			(property "Description" "SMD Multilayer Ceramic Capacitor, 10000 pF, 50 V, 0402 [1005 Metric], ± 10%, X7R, GRM Series"
				(at 0 0 0)
				(effects
					(font
						(size 1.27 1.27)
					)
					(hide yes)
				)
			)
			(property "MPN" "GRM155R71H103KA88D"
				(at 20.32 -17.78 0)
				(effects
					(font
						(size 1.27 1.27)
						(thickness 0.15)
					)
					(justify left bottom)
					(hide yes)
				)
			)
			(property "Manufacturer" "Murata"
				(at 20.32 -20.32 0)
				(effects
					(font
						(size 1.27 1.27)
						(thickness 0.15)
					)
					(justify left bottom)
					(hide yes)
				)
			)
			(property "License" "Apache-2.0"
				(at 20.32 -22.86 0)
				(effects
					(font
						(size 1.27 1.27)
						(thickness 0.15)
					)
					(justify left bottom)
					(hide yes)
				)
			)
			(property "Author" "Antmicro"
				(at 20.32 -25.4 0)
				(effects
					(font
						(size 1.27 1.27)
						(thickness 0.15)
					)
					(justify left bottom)
					(hide yes)
				)
			)
			(property "Val" "10n"
				(at 20.32 -7.62 0)
				(effects
					(font
						(size 1.27 1.27)
						(thickness 0.15)
					)
					(justify left bottom)
				)
			)
			(property "Voltage" "50V"
				(at 20.32 -27.94 0)
				(effects
					(font
						(size 1.27 1.27)
					)
					(justify left bottom)
					(hide yes)
				)
			)
			(property "Dielectric" "X7R"
				(at 20.32 -30.48 0)
				(effects
					(font
						(size 1.27 1.27)
					)
					(justify left bottom)
					(hide yes)
				)
			)
			(property "ki_keywords" "0402, SMT, CAPACITOR, PASSIVE"
				(at 0 0 0)
				(effects
					(font
						(size 1.27 1.27)
					)
					(hide yes)
				)
			)
			(symbol "C_10n_0402_0_1"
				(polyline
					(pts
						(xy 2.032 -1.524) (xy 2.032 1.524)
					)
					(stroke
						(width 0.3048)
						(type default)
					)
					(fill
						(type none)
					)
				)
				(polyline
					(pts
						(xy 3.048 -1.524) (xy 3.048 1.524)
					)
					(stroke
						(width 0.3302)
						(type default)
					)
					(fill
						(type none)
					)
				)
			)
			(symbol "C_10n_0402_1_1"
				(pin passive line
					(at 0 0 0)
					(length 2.032)
					(name "~"
						(effects
							(font
								(size 1.27 1.27)
							)
						)
					)
					(number "1"
						(effects
							(font
								(size 1.27 1.27)
							)
						)
					)
				)
				(pin passive line
					(at 5.08 0 180)
					(length 2.032)
					(name "~"
						(effects
							(font
								(size 1.27 1.27)
							)
						)
					)
					(number "2"
						(effects
							(font
								(size 1.27 1.27)
							)
						)
					)
				)
			)
		)
	(symbol "antmicroCapacitors0402:C_10p_0402"
			(pin_numbers
				(hide yes)
			)
			(pin_names
				(hide yes)
			)
			(exclude_from_sim no)
			(in_bom yes)
			(on_board yes)
			(property "Reference" "C"
				(at 20.32 -5.08 0)
				(effects
					(font
						(size 1.27 1.27)
						(thickness 0.15)
					)
					(justify left bottom)
				)
			)
			(property "Value" "C_10p_0402"
				(at 20.32 -10.16 0)
				(effects
					(font
						(size 1.27 1.27)
						(thickness 0.15)
					)
					(justify left bottom)
					(hide yes)
				)
			)
			(property "Footprint" "antmicro-footprints:C_0402_1005Metric"
				(at 20.32 -12.7 0)
				(effects
					(font
						(size 1.27 1.27)
						(thickness 0.15)
					)
					(justify left bottom)
					(hide yes)
				)
			)
			(property "Datasheet" "https://www.murata.com/products/productdetail?partno=GCM1555C1H100GA16%23"
				(at 20.32 -15.24 0)
				(effects
					(font
						(size 1.27 1.27)
						(thickness 0.15)
					)
					(justify left bottom)
					(hide yes)
				)
			)
			(property "Description" "SMD Multilayer Ceramic Capacitor, 10 pF, 50 V, 0402 [1005 Metric], ± 2%, C0G / NP0, GCM"
				(at 0 0 0)
				(effects
					(font
						(size 1.27 1.27)
					)
					(hide yes)
				)
			)
			(property "MPN" "GCM1555C1H100GA16D"
				(at 20.32 -17.78 0)
				(effects
					(font
						(size 1.27 1.27)
						(thickness 0.15)
					)
					(justify left bottom)
					(hide yes)
				)
			)
			(property "Manufacturer" "Murata"
				(at 20.32 -20.32 0)
				(effects
					(font
						(size 1.27 1.27)
						(thickness 0.15)
					)
					(justify left bottom)
					(hide yes)
				)
			)
			(property "License" "Apache-2.0"
				(at 20.32 -22.86 0)
				(effects
					(font
						(size 1.27 1.27)
						(thickness 0.15)
					)
					(justify left bottom)
					(hide yes)
				)
			)
			(property "Author" "Antmicro"
				(at 20.32 -25.4 0)
				(effects
					(font
						(size 1.27 1.27)
						(thickness 0.15)
					)
					(justify left bottom)
					(hide yes)
				)
			)
			(property "Val" "10p"
				(at 20.32 -7.62 0)
				(effects
					(font
						(size 1.27 1.27)
						(thickness 0.15)
					)
					(justify left bottom)
				)
			)
			(property "Voltage" "50V"
				(at 20.32 -27.94 0)
				(effects
					(font
						(size 1.27 1.27)
					)
					(justify left bottom)
					(hide yes)
				)
			)
			(property "Dielectric" "C0G"
				(at 20.32 -30.48 0)
				(effects
					(font
						(size 1.27 1.27)
					)
					(justify left bottom)
					(hide yes)
				)
			)
			(property "ki_keywords" "0402, SMT, CAPACITOR, PASSIVE"
				(at 0 0 0)
				(effects
					(font
						(size 1.27 1.27)
					)
					(hide yes)
				)
			)
			(symbol "C_10p_0402_0_1"
				(polyline
					(pts
						(xy 2.032 -1.524) (xy 2.032 1.524)
					)
					(stroke
						(width 0.3048)
						(type default)
					)
					(fill
						(type none)
					)
				)
				(polyline
					(pts
						(xy 3.048 -1.524) (xy 3.048 1.524)
					)
					(stroke
						(width 0.3302)
						(type default)
					)
					(fill
						(type none)
					)
				)
			)
			(symbol "C_10p_0402_1_1"
				(pin passive line
					(at 0 0 0)
					(length 2.032)
					(name "~"
						(effects
							(font
								(size 1.27 1.27)
							)
						)
					)
					(number "1"
						(effects
							(font
								(size 1.27 1.27)
							)
						)
					)
				)
				(pin passive line
					(at 5.08 0 180)
					(length 2.032)
					(name "~"
						(effects
							(font
								(size 1.27 1.27)
							)
						)
					)
					(number "2"
						(effects
							(font
								(size 1.27 1.27)
							)
						)
					)
				)
			)
		)
	(symbol "antmicroCapacitors0402:C_10u_0402"
			(pin_numbers
				(hide yes)
			)
			(pin_names
				(hide yes)
			)
			(exclude_from_sim no)
			(in_bom yes)
			(on_board yes)
			(property "Reference" "C"
				(at 20.32 -5.08 0)
				(effects
					(font
						(size 1.27 1.27)
						(thickness 0.15)
					)
					(justify left bottom)
				)
			)
			(property "Value" "C_10u_0402"
				(at 20.32 -10.16 0)
				(effects
					(font
						(size 1.27 1.27)
						(thickness 0.15)
					)
					(justify left bottom)
					(hide yes)
				)
			)
			(property "Footprint" "antmicro-footprints:C_0402_1005Metric"
				(at 20.32 -12.7 0)
				(effects
					(font
						(size 1.27 1.27)
						(thickness 0.15)
					)
					(justify left bottom)
					(hide yes)
				)
			)
			(property "Datasheet" "https://www.yageo.com/en/Chart/Download/pdf/CC0402MRX5R5BB106"
				(at 20.32 -15.24 0)
				(effects
					(font
						(size 1.27 1.27)
						(thickness 0.15)
					)
					(justify left bottom)
					(hide yes)
				)
			)
			(property "Description" "SMD Multilayer Ceramic Capacitor, 10 µF, 6.3 V, 0402 [1005 Metric], ± 20%, X5R, CC Series"
				(at 0 0 0)
				(effects
					(font
						(size 1.27 1.27)
					)
					(hide yes)
				)
			)
			(property "MPN" "CC0402MRX5R5BB106"
				(at 20.32 -17.78 0)
				(effects
					(font
						(size 1.27 1.27)
						(thickness 0.15)
					)
					(justify left bottom)
					(hide yes)
				)
			)
			(property "Manufacturer" "YAGEO"
				(at 20.32 -20.32 0)
				(effects
					(font
						(size 1.27 1.27)
						(thickness 0.15)
					)
					(justify left bottom)
					(hide yes)
				)
			)
			(property "License" "Apache-2.0"
				(at 20.32 -22.86 0)
				(effects
					(font
						(size 1.27 1.27)
						(thickness 0.15)
					)
					(justify left bottom)
					(hide yes)
				)
			)
			(property "Author" "Antmicro"
				(at 20.32 -25.4 0)
				(effects
					(font
						(size 1.27 1.27)
						(thickness 0.15)
					)
					(justify left bottom)
					(hide yes)
				)
			)
			(property "Val" "10u"
				(at 20.32 -7.62 0)
				(effects
					(font
						(size 1.27 1.27)
						(thickness 0.15)
					)
					(justify left bottom)
				)
			)
			(property "Voltage" ""
				(at 20.32 -27.94 0)
				(effects
					(font
						(size 1.27 1.27)
					)
					(justify left bottom)
					(hide yes)
				)
			)
			(property "Dielectric" ""
				(at 20.32 -30.48 0)
				(effects
					(font
						(size 1.27 1.27)
					)
					(justify left bottom)
					(hide yes)
				)
			)
			(property "ki_keywords" "0402, SMT, CAPACITOR, PASSIVE, MLCC, CERAMIC"
				(at 0 0 0)
				(effects
					(font
						(size 1.27 1.27)
					)
					(hide yes)
				)
			)
			(symbol "C_10u_0402_0_1"
				(polyline
					(pts
						(xy 2.032 -1.524) (xy 2.032 1.524)
					)
					(stroke
						(width 0.3048)
						(type default)
					)
					(fill
						(type none)
					)
				)
				(polyline
					(pts
						(xy 3.048 -1.524) (xy 3.048 1.524)
					)
					(stroke
						(width 0.3302)
						(type default)
					)
					(fill
						(type none)
					)
				)
			)
			(symbol "C_10u_0402_1_1"
				(pin passive line
					(at 0 0 0)
					(length 2.032)
					(name "~"
						(effects
							(font
								(size 1.27 1.27)
							)
						)
					)
					(number "1"
						(effects
							(font
								(size 1.27 1.27)
							)
						)
					)
				)
				(pin passive line
					(at 5.08 0 180)
					(length 2.032)
					(name "~"
						(effects
							(font
								(size 1.27 1.27)
							)
						)
					)
					(number "2"
						(effects
							(font
								(size 1.27 1.27)
							)
						)
					)
				)
			)
		)
	(symbol "antmicroCapacitors0402:C_12p_0402"
			(pin_numbers
				(hide yes)
			)
			(pin_names
				(hide yes)
			)
			(exclude_from_sim no)
			(in_bom yes)
			(on_board yes)
			(property "Reference" "C"
				(at 20.32 -5.08 0)
				(effects
					(font
						(size 1.27 1.27)
						(thickness 0.15)
					)
					(justify left bottom)
				)
			)
			(property "Value" "C_12p_0402"
				(at 20.32 -10.16 0)
				(effects
					(font
						(size 1.27 1.27)
						(thickness 0.15)
					)
					(justify left bottom)
					(hide yes)
				)
			)
			(property "Footprint" "antmicro-footprints:C_0402_1005Metric"
				(at 20.32 -12.7 0)
				(effects
					(font
						(size 1.27 1.27)
						(thickness 0.15)
					)
					(justify left bottom)
					(hide yes)
				)
			)
			(property "Datasheet" "https://product.tdk.com/en/search/capacitor/ceramic/mlcc/info?part_no=CGA2B2C0G1H120J050BA"
				(at 20.32 -15.24 0)
				(effects
					(font
						(size 1.27 1.27)
						(thickness 0.15)
					)
					(justify left bottom)
					(hide yes)
				)
			)
			(property "Description" "SMD Multilayer Ceramic Capacitor, 12 pF, 50 V, 0402 [1005 Metric], ± 5%, C0G / NP0, CGA"
				(at 20.32 -33.02 0)
				(effects
					(font
						(size 1.27 1.27)
					)
					(justify left bottom)
					(hide yes)
				)
			)
			(property "MPN" "CGA2B2C0G1H120J050BA"
				(at 20.32 -17.78 0)
				(effects
					(font
						(size 1.27 1.27)
						(thickness 0.15)
					)
					(justify left bottom)
					(hide yes)
				)
			)
			(property "Manufacturer" "TDK"
				(at 20.32 -20.32 0)
				(effects
					(font
						(size 1.27 1.27)
						(thickness 0.15)
					)
					(justify left bottom)
					(hide yes)
				)
			)
			(property "License" "Apache-2.0"
				(at 20.32 -22.86 0)
				(effects
					(font
						(size 1.27 1.27)
						(thickness 0.15)
					)
					(justify left bottom)
					(hide yes)
				)
			)
			(property "Author" "Antmicro"
				(at 20.32 -25.4 0)
				(effects
					(font
						(size 1.27 1.27)
						(thickness 0.15)
					)
					(justify left bottom)
					(hide yes)
				)
			)
			(property "Val" "12p"
				(at 20.32 -7.62 0)
				(effects
					(font
						(size 1.27 1.27)
						(thickness 0.15)
					)
					(justify left bottom)
				)
			)
			(property "Voltage" ""
				(at 20.32 -27.94 0)
				(effects
					(font
						(size 1.27 1.27)
					)
					(justify left bottom)
					(hide yes)
				)
			)
			(property "Dielectric" ""
				(at 20.32 -30.48 0)
				(effects
					(font
						(size 1.27 1.27)
					)
					(justify left bottom)
					(hide yes)
				)
			)
			(property "ki_keywords" "0402, SMT, CAPACITOR, PASSIVE, CERAMIC, MLCC"
				(at 0 0 0)
				(effects
					(font
						(size 1.27 1.27)
					)
					(hide yes)
				)
			)
			(symbol "C_12p_0402_0_1"
				(polyline
					(pts
						(xy 2.032 -1.524) (xy 2.032 1.524)
					)
					(stroke
						(width 0.3048)
						(type default)
					)
					(fill
						(type none)
					)
				)
				(polyline
					(pts
						(xy 3.048 -1.524) (xy 3.048 1.524)
					)
					(stroke
						(width 0.3302)
						(type default)
					)
					(fill
						(type none)
					)
				)
			)
			(symbol "C_12p_0402_1_1"
				(pin passive line
					(at 0 0 0)
					(length 2.032)
					(name "~"
						(effects
							(font
								(size 1.27 1.27)
							)
						)
					)
					(number "1"
						(effects
							(font
								(size 1.27 1.27)
							)
						)
					)
				)
				(pin passive line
					(at 5.08 0 180)
					(length 2.032)
					(name "~"
						(effects
							(font
								(size 1.27 1.27)
							)
						)
					)
					(number "2"
						(effects
							(font
								(size 1.27 1.27)
							)
						)
					)
				)
			)
		)
	(symbol "antmicroCapacitors0402:C_18p_0402"
			(pin_numbers
				(hide yes)
			)
			(pin_names
				(hide yes)
			)
			(exclude_from_sim no)
			(in_bom yes)
			(on_board yes)
			(property "Reference" "C"
				(at 20.32 -5.08 0)
				(effects
					(font
						(size 1.27 1.27)
						(thickness 0.15)
					)
					(justify left bottom)
				)
			)
			(property "Value" "C_18p_0402"
				(at 20.32 -10.16 0)
				(effects
					(font
						(size 1.27 1.27)
						(thickness 0.15)
					)
					(justify left bottom)
					(hide yes)
				)
			)
			(property "Footprint" "antmicro-footprints:C_0402_1005Metric"
				(at 20.32 -12.7 0)
				(effects
					(font
						(size 1.27 1.27)
						(thickness 0.15)
					)
					(justify left bottom)
					(hide yes)
				)
			)
			(property "Datasheet" "https://product.samsungsem.com/mlcc/CL05C180JB51PN.do"
				(at 20.32 -15.24 0)
				(effects
					(font
						(size 1.27 1.27)
						(thickness 0.15)
					)
					(justify left bottom)
					(hide yes)
				)
			)
			(property "Description" "SMD Multilayer Ceramic Capacitor, 18 pF, 50 V, 0402 [1005 Metric], ± 5%, C0G / NP0, MC"
				(at 0 0 0)
				(effects
					(font
						(size 1.27 1.27)
					)
					(hide yes)
				)
			)
			(property "MPN" "CL05C180JB51PNC"
				(at 20.32 -17.78 0)
				(effects
					(font
						(size 1.27 1.27)
						(thickness 0.15)
					)
					(justify left bottom)
					(hide yes)
				)
			)
			(property "Manufacturer" "Samsung Electro-Mechanics"
				(at 20.32 -20.32 0)
				(effects
					(font
						(size 1.27 1.27)
						(thickness 0.15)
					)
					(justify left bottom)
					(hide yes)
				)
			)
			(property "License" "Apache-2.0"
				(at 20.32 -22.86 0)
				(effects
					(font
						(size 1.27 1.27)
						(thickness 0.15)
					)
					(justify left bottom)
					(hide yes)
				)
			)
			(property "Author" "Antmicro"
				(at 20.32 -25.4 0)
				(effects
					(font
						(size 1.27 1.27)
						(thickness 0.15)
					)
					(justify left bottom)
					(hide yes)
				)
			)
			(property "Val" "18p"
				(at 20.32 -7.62 0)
				(effects
					(font
						(size 1.27 1.27)
						(thickness 0.15)
					)
					(justify left bottom)
				)
			)
			(property "Voltage" ""
				(at 20.32 -27.94 0)
				(effects
					(font
						(size 1.27 1.27)
					)
					(justify left bottom)
					(hide yes)
				)
			)
			(property "Dielectric" ""
				(at 20.32 -30.48 0)
				(effects
					(font
						(size 1.27 1.27)
					)
					(justify left bottom)
					(hide yes)
				)
			)
			(property "ki_keywords" "0402, SMT, CAPACITOR, PASSIVE"
				(at 0 0 0)
				(effects
					(font
						(size 1.27 1.27)
					)
					(hide yes)
				)
			)
			(symbol "C_18p_0402_0_1"
				(polyline
					(pts
						(xy 2.032 -1.524) (xy 2.032 1.524)
					)
					(stroke
						(width 0.3048)
						(type default)
					)
					(fill
						(type none)
					)
				)
				(polyline
					(pts
						(xy 3.048 -1.524) (xy 3.048 1.524)
					)
					(stroke
						(width 0.3302)
						(type default)
					)
					(fill
						(type none)
					)
				)
			)
			(symbol "C_18p_0402_1_1"
				(pin passive line
					(at 0 0 0)
					(length 2.032)
					(name "~"
						(effects
							(font
								(size 1.27 1.27)
							)
						)
					)
					(number "1"
						(effects
							(font
								(size 1.27 1.27)
							)
						)
					)
				)
				(pin passive line
					(at 5.08 0 180)
					(length 2.032)
					(name "~"
						(effects
							(font
								(size 1.27 1.27)
							)
						)
					)
					(number "2"
						(effects
							(font
								(size 1.27 1.27)
							)
						)
					)
				)
			)
		)
	(symbol "antmicroCapacitors0402:C_1n_0402"
			(pin_numbers
				(hide yes)
			)
			(pin_names
				(hide yes)
			)
			(exclude_from_sim no)
			(in_bom yes)
			(on_board yes)
			(property "Reference" "C"
				(at 20.32 -5.08 0)
				(effects
					(font
						(size 1.27 1.27)
						(thickness 0.15)
					)
					(justify left bottom)
				)
			)
			(property "Value" "C_1n_0402"
				(at 20.32 -10.16 0)
				(effects
					(font
						(size 1.27 1.27)
						(thickness 0.15)
					)
					(justify left bottom)
					(hide yes)
				)
			)
			(property "Footprint" "antmicro-footprints:C_0402_1005Metric"
				(at 20.32 -12.7 0)
				(effects
					(font
						(size 1.27 1.27)
						(thickness 0.15)
					)
					(justify left bottom)
					(hide yes)
				)
			)
			(property "Datasheet" "https://www.murata.com/products/productdetail?partno=GRM1555C1H102JA01%23"
				(at 20.32 -15.24 0)
				(effects
					(font
						(size 1.27 1.27)
						(thickness 0.15)
					)
					(justify left bottom)
					(hide yes)
				)
			)
			(property "Description" "SMD Multilayer Ceramic Capacitor, 1000 pF, 50 V, 0402 [1005 Metric], ± 5%, C0G / NP0, GRM Series"
				(at 20.32 -33.02 0)
				(effects
					(font
						(size 1.27 1.27)
					)
					(justify left bottom)
					(hide yes)
				)
			)
			(property "MPN" "GRM1555C1H102JA01D"
				(at 20.32 -17.78 0)
				(effects
					(font
						(size 1.27 1.27)
						(thickness 0.15)
					)
					(justify left bottom)
					(hide yes)
				)
			)
			(property "Manufacturer" "Murata"
				(at 20.32 -20.32 0)
				(effects
					(font
						(size 1.27 1.27)
						(thickness 0.15)
					)
					(justify left bottom)
					(hide yes)
				)
			)
			(property "License" "Apache-2.0"
				(at 20.32 -22.86 0)
				(effects
					(font
						(size 1.27 1.27)
						(thickness 0.15)
					)
					(justify left bottom)
					(hide yes)
				)
			)
			(property "Author" "Antmicro"
				(at 20.32 -25.4 0)
				(effects
					(font
						(size 1.27 1.27)
						(thickness 0.15)
					)
					(justify left bottom)
					(hide yes)
				)
			)
			(property "Val" "1n"
				(at 20.32 -7.62 0)
				(effects
					(font
						(size 1.27 1.27)
						(thickness 0.15)
					)
					(justify left bottom)
				)
			)
			(property "Voltage" "50V"
				(at 20.32 -27.94 0)
				(effects
					(font
						(size 1.27 1.27)
					)
					(justify left bottom)
					(hide yes)
				)
			)
			(property "Dielectric" "C0G"
				(at 20.32 -30.48 0)
				(effects
					(font
						(size 1.27 1.27)
					)
					(justify left bottom)
					(hide yes)
				)
			)
			(property "ki_keywords" "0402, SMT, CAPACITOR, PASSIVE, CERAMIC, MLCC"
				(at 0 0 0)
				(effects
					(font
						(size 1.27 1.27)
					)
					(hide yes)
				)
			)
			(symbol "C_1n_0402_0_1"
				(polyline
					(pts
						(xy 2.032 -1.524) (xy 2.032 1.524)
					)
					(stroke
						(width 0.3048)
						(type default)
					)
					(fill
						(type none)
					)
				)
				(polyline
					(pts
						(xy 3.048 -1.524) (xy 3.048 1.524)
					)
					(stroke
						(width 0.3302)
						(type default)
					)
					(fill
						(type none)
					)
				)
			)
			(symbol "C_1n_0402_1_1"
				(pin passive line
					(at 0 0 0)
					(length 2.032)
					(name "~"
						(effects
							(font
								(size 1.27 1.27)
							)
						)
					)
					(number "1"
						(effects
							(font
								(size 1.27 1.27)
							)
						)
					)
				)
				(pin passive line
					(at 5.08 0 180)
					(length 2.032)
					(name "~"
						(effects
							(font
								(size 1.27 1.27)
							)
						)
					)
					(number "2"
						(effects
							(font
								(size 1.27 1.27)
							)
						)
					)
				)
			)
		)
	(symbol "antmicroCapacitors0402:C_1u_0402"
			(pin_numbers
				(hide yes)
			)
			(pin_names
				(hide yes)
			)
			(exclude_from_sim no)
			(in_bom yes)
			(on_board yes)
			(property "Reference" "C"
				(at 20.32 -5.08 0)
				(effects
					(font
						(size 1.27 1.27)
						(thickness 0.15)
					)
					(justify left bottom)
				)
			)
			(property "Value" "C_1u_0402"
				(at 20.32 -10.16 0)
				(effects
					(font
						(size 1.27 1.27)
						(thickness 0.15)
					)
					(justify left bottom)
					(hide yes)
				)
			)
			(property "Footprint" "antmicro-footprints:C_0402_1005Metric"
				(at 20.32 -12.7 0)
				(effects
					(font
						(size 1.27 1.27)
						(thickness 0.15)
					)
					(justify left bottom)
					(hide yes)
				)
			)
			(property "Datasheet" "https://product.tdk.com/en/search/capacitor/ceramic/mlcc/info?part_no=C1005X6S1A105K050BC"
				(at 20.32 -15.24 0)
				(effects
					(font
						(size 1.27 1.27)
						(thickness 0.15)
					)
					(justify left bottom)
					(hide yes)
				)
			)
			(property "Description" "SMD Multilayer Ceramic Capacitor, 1 µF, 10 V, 0402 [1005 Metric], ± 10%, X6S, C"
				(at 0 0 0)
				(effects
					(font
						(size 1.27 1.27)
					)
					(hide yes)
				)
			)
			(property "MPN" "C1005X6S1A105K050BC"
				(at 20.32 -17.78 0)
				(effects
					(font
						(size 1.27 1.27)
						(thickness 0.15)
					)
					(justify left bottom)
					(hide yes)
				)
			)
			(property "Manufacturer" "TDK"
				(at 20.32 -20.32 0)
				(effects
					(font
						(size 1.27 1.27)
						(thickness 0.15)
					)
					(justify left bottom)
					(hide yes)
				)
			)
			(property "License" "Apache-2.0"
				(at 20.32 -22.86 0)
				(effects
					(font
						(size 1.27 1.27)
						(thickness 0.15)
					)
					(justify left bottom)
					(hide yes)
				)
			)
			(property "Author" "Antmicro"
				(at 20.32 -25.4 0)
				(effects
					(font
						(size 1.27 1.27)
						(thickness 0.15)
					)
					(justify left bottom)
					(hide yes)
				)
			)
			(property "Val" "1u"
				(at 20.32 -7.62 0)
				(effects
					(font
						(size 1.27 1.27)
						(thickness 0.15)
					)
					(justify left bottom)
				)
			)
			(property "Voltage" ""
				(at 20.32 -27.94 0)
				(effects
					(font
						(size 1.27 1.27)
					)
					(justify left bottom)
					(hide yes)
				)
			)
			(property "Dielectric" ""
				(at 20.32 -30.48 0)
				(effects
					(font
						(size 1.27 1.27)
					)
					(justify left bottom)
					(hide yes)
				)
			)
			(property "ki_keywords" "0402, SMT, CAPACITOR, PASSIVE, CERAMIC, MLCC"
				(at 0 0 0)
				(effects
					(font
						(size 1.27 1.27)
					)
					(hide yes)
				)
			)
			(symbol "C_1u_0402_0_1"
				(polyline
					(pts
						(xy 2.032 -1.524) (xy 2.032 1.524)
					)
					(stroke
						(width 0.3048)
						(type default)
					)
					(fill
						(type none)
					)
				)
				(polyline
					(pts
						(xy 3.048 -1.524) (xy 3.048 1.524)
					)
					(stroke
						(width 0.3302)
						(type default)
					)
					(fill
						(type none)
					)
				)
			)
			(symbol "C_1u_0402_1_1"
				(pin passive line
					(at 0 0 0)
					(length 2.032)
					(name "~"
						(effects
							(font
								(size 1.27 1.27)
							)
						)
					)
					(number "1"
						(effects
							(font
								(size 1.27 1.27)
							)
						)
					)
				)
				(pin passive line
					(at 5.08 0 180)
					(length 2.032)
					(name "~"
						(effects
							(font
								(size 1.27 1.27)
							)
						)
					)
					(number "2"
						(effects
							(font
								(size 1.27 1.27)
							)
						)
					)
				)
			)
		)
	(symbol "antmicroCapacitors0402:C_1u_25V_0402"
			(pin_numbers
				(hide yes)
			)
			(pin_names
				(hide yes)
			)
			(exclude_from_sim no)
			(in_bom yes)
			(on_board yes)
			(property "Reference" "C"
				(at 20.32 -5.08 0)
				(effects
					(font
						(size 1.27 1.27)
						(thickness 0.15)
					)
					(justify left bottom)
				)
			)
			(property "Value" "C_1u_25V_0402"
				(at 20.32 -10.16 0)
				(effects
					(font
						(size 1.27 1.27)
						(thickness 0.15)
					)
					(justify left bottom)
					(hide yes)
				)
			)
			(property "Footprint" "antmicro-footprints:C_0402_1005Metric"
				(at 20.32 -12.7 0)
				(effects
					(font
						(size 1.27 1.27)
						(thickness 0.15)
					)
					(justify left bottom)
					(hide yes)
				)
			)
			(property "Datasheet" "https://www.murata.com/products/productdetail?partno=GRM155R61E105KE11%23"
				(at 20.32 -15.24 0)
				(effects
					(font
						(size 1.27 1.27)
						(thickness 0.15)
					)
					(justify left bottom)
					(hide yes)
				)
			)
			(property "Description" "SMD Multilayer Ceramic Capacitor, 1 µF, 25 V, 0402 [1005 Metric], ± 10%, X5R, GRM Series"
				(at 0 0 0)
				(effects
					(font
						(size 1.27 1.27)
					)
					(hide yes)
				)
			)
			(property "MPN" "GRM155R61E105KE11J"
				(at 20.32 -17.78 0)
				(effects
					(font
						(size 1.27 1.27)
						(thickness 0.15)
					)
					(justify left bottom)
					(hide yes)
				)
			)
			(property "Manufacturer" "Murata"
				(at 20.32 -20.32 0)
				(effects
					(font
						(size 1.27 1.27)
						(thickness 0.15)
					)
					(justify left bottom)
					(hide yes)
				)
			)
			(property "License" "Apache-2.0"
				(at 20.32 -22.86 0)
				(effects
					(font
						(size 1.27 1.27)
						(thickness 0.15)
					)
					(justify left bottom)
					(hide yes)
				)
			)
			(property "Author" "Antmicro"
				(at 20.32 -25.4 0)
				(effects
					(font
						(size 1.27 1.27)
						(thickness 0.15)
					)
					(justify left bottom)
					(hide yes)
				)
			)
			(property "Val" "1u"
				(at 20.32 -7.62 0)
				(effects
					(font
						(size 1.27 1.27)
						(thickness 0.15)
					)
					(justify left bottom)
				)
			)
			(property "Voltage" "25V"
				(at 20.32 -27.94 0)
				(effects
					(font
						(size 1.27 1.27)
					)
					(justify left bottom)
					(hide yes)
				)
			)
			(property "Dielectric" "X5R"
				(at 20.32 -30.48 0)
				(effects
					(font
						(size 1.27 1.27)
					)
					(justify left bottom)
					(hide yes)
				)
			)
			(property "ki_keywords" "0402, SMT, CAPACITOR, PASSIVE, CERAMIC"
				(at 0 0 0)
				(effects
					(font
						(size 1.27 1.27)
					)
					(hide yes)
				)
			)
			(symbol "C_1u_25V_0402_0_1"
				(polyline
					(pts
						(xy 2.032 -1.524) (xy 2.032 1.524)
					)
					(stroke
						(width 0.3048)
						(type default)
					)
					(fill
						(type none)
					)
				)
				(polyline
					(pts
						(xy 3.048 -1.524) (xy 3.048 1.524)
					)
					(stroke
						(width 0.3302)
						(type default)
					)
					(fill
						(type none)
					)
				)
			)
			(symbol "C_1u_25V_0402_1_1"
				(pin passive line
					(at 0 0 0)
					(length 2.032)
					(name "~"
						(effects
							(font
								(size 1.27 1.27)
							)
						)
					)
					(number "1"
						(effects
							(font
								(size 1.27 1.27)
							)
						)
					)
				)
				(pin passive line
					(at 5.08 0 180)
					(length 2.032)
					(name "~"
						(effects
							(font
								(size 1.27 1.27)
							)
						)
					)
					(number "2"
						(effects
							(font
								(size 1.27 1.27)
							)
						)
					)
				)
			)
		)
	(symbol "antmicroCapacitors0402:C_2u2_0402"
			(pin_numbers
				(hide yes)
			)
			(pin_names
				(hide yes)
			)
			(exclude_from_sim no)
			(in_bom yes)
			(on_board yes)
			(property "Reference" "C"
				(at 20.32 -5.08 0)
				(effects
					(font
						(size 1.27 1.27)
						(thickness 0.15)
					)
					(justify left bottom)
				)
			)
			(property "Value" "C_2u2_0402"
				(at 20.32 -10.16 0)
				(effects
					(font
						(size 1.27 1.27)
						(thickness 0.15)
					)
					(justify left bottom)
					(hide yes)
				)
			)
			(property "Footprint" "antmicro-footprints:C_0402_1005Metric"
				(at 20.32 -12.7 0)
				(effects
					(font
						(size 1.27 1.27)
						(thickness 0.15)
					)
					(justify left bottom)
					(hide yes)
				)
			)
			(property "Datasheet" "https://product.tdk.com/en/search/capacitor/ceramic/mlcc/info?part_no=C1005X5R1A225K050BC"
				(at 20.32 -15.24 0)
				(effects
					(font
						(size 1.27 1.27)
						(thickness 0.15)
					)
					(justify left bottom)
					(hide yes)
				)
			)
			(property "Description" "SMD Multilayer Ceramic Capacitor, 2.2 µF, 10 V, 0402 [1005 Metric], ± 10%, X5R, C"
				(at 0 0 0)
				(effects
					(font
						(size 1.27 1.27)
					)
					(hide yes)
				)
			)
			(property "MPN" "C1005X5R1A225K050BC"
				(at 20.32 -17.78 0)
				(effects
					(font
						(size 1.27 1.27)
						(thickness 0.15)
					)
					(justify left bottom)
					(hide yes)
				)
			)
			(property "Manufacturer" "TDK"
				(at 20.32 -20.32 0)
				(effects
					(font
						(size 1.27 1.27)
						(thickness 0.15)
					)
					(justify left bottom)
					(hide yes)
				)
			)
			(property "License" "Apache-2.0"
				(at 20.32 -22.86 0)
				(effects
					(font
						(size 1.27 1.27)
						(thickness 0.15)
					)
					(justify left bottom)
					(hide yes)
				)
			)
			(property "Author" "Antmicro"
				(at 20.32 -25.4 0)
				(effects
					(font
						(size 1.27 1.27)
						(thickness 0.15)
					)
					(justify left bottom)
					(hide yes)
				)
			)
			(property "Val" "2u2"
				(at 20.32 -7.62 0)
				(effects
					(font
						(size 1.27 1.27)
						(thickness 0.15)
					)
					(justify left bottom)
				)
			)
			(property "Voltage" ""
				(at 20.32 -27.94 0)
				(effects
					(font
						(size 1.27 1.27)
					)
					(justify left bottom)
					(hide yes)
				)
			)
			(property "Dielectric" ""
				(at 20.32 -30.48 0)
				(effects
					(font
						(size 1.27 1.27)
					)
					(justify left bottom)
					(hide yes)
				)
			)
			(property "ki_keywords" "0402, SMT, CAPACITOR, PASSIVE, CERAMIC, MLCC"
				(at 0 0 0)
				(effects
					(font
						(size 1.27 1.27)
					)
					(hide yes)
				)
			)
			(symbol "C_2u2_0402_0_1"
				(polyline
					(pts
						(xy 2.032 -1.524) (xy 2.032 1.524)
					)
					(stroke
						(width 0.3048)
						(type default)
					)
					(fill
						(type none)
					)
				)
				(polyline
					(pts
						(xy 3.048 -1.524) (xy 3.048 1.524)
					)
					(stroke
						(width 0.3302)
						(type default)
					)
					(fill
						(type none)
					)
				)
			)
			(symbol "C_2u2_0402_1_1"
				(pin passive line
					(at 0 0 0)
					(length 2.032)
					(name "~"
						(effects
							(font
								(size 1.27 1.27)
							)
						)
					)
					(number "1"
						(effects
							(font
								(size 1.27 1.27)
							)
						)
					)
				)
				(pin passive line
					(at 5.08 0 180)
					(length 2.032)
					(name "~"
						(effects
							(font
								(size 1.27 1.27)
							)
						)
					)
					(number "2"
						(effects
							(font
								(size 1.27 1.27)
							)
						)
					)
				)
			)
		)
	(symbol "antmicroCapacitors0402:C_36p_0402"
			(pin_numbers
				(hide yes)
			)
			(pin_names
				(hide yes)
			)
			(exclude_from_sim no)
			(in_bom yes)
			(on_board yes)
			(property "Reference" "C"
				(at 20.32 -5.08 0)
				(effects
					(font
						(size 1.27 1.27)
						(thickness 0.15)
					)
					(justify left bottom)
				)
			)
			(property "Value" "C_36p_0402"
				(at 20.32 -10.16 0)
				(effects
					(font
						(size 1.27 1.27)
						(thickness 0.15)
					)
					(justify left bottom)
					(hide yes)
				)
			)
			(property "Footprint" "antmicro-footprints:C_0402_1005Metric"
				(at 20.32 -12.7 0)
				(effects
					(font
						(size 1.27 1.27)
						(thickness 0.15)
					)
					(justify left bottom)
					(hide yes)
				)
			)
			(property "Datasheet" "https://eu.mouser.com/datasheet/3/5926/1/C0GNP0_Dielectric.pdf"
				(at 20.32 -15.24 0)
				(effects
					(font
						(size 1.27 1.27)
						(thickness 0.15)
					)
					(justify left bottom)
					(hide yes)
				)
			)
			(property "Description" "Multilayer Ceramic Capacitors MLCC, 36 pF, 25V, 0402, C0G, 5%"
				(at 20.32 -33.02 0)
				(effects
					(font
						(size 1.27 1.27)
					)
					(justify left bottom)
					(hide yes)
				)
			)
			(property "MPN" "04023A360JAT2A"
				(at 20.32 -17.78 0)
				(effects
					(font
						(size 1.27 1.27)
						(thickness 0.15)
					)
					(justify left bottom)
					(hide yes)
				)
			)
			(property "Manufacturer" "KYOCERA AVX"
				(at 20.32 -20.32 0)
				(effects
					(font
						(size 1.27 1.27)
						(thickness 0.15)
					)
					(justify left bottom)
					(hide yes)
				)
			)
			(property "License" "Apache-2.0"
				(at 20.32 -22.86 0)
				(effects
					(font
						(size 1.27 1.27)
						(thickness 0.15)
					)
					(justify left bottom)
					(hide yes)
				)
			)
			(property "Author" "Antmicro"
				(at 20.32 -25.4 0)
				(effects
					(font
						(size 1.27 1.27)
						(thickness 0.15)
					)
					(justify left bottom)
					(hide yes)
				)
			)
			(property "Val" "36pF"
				(at 20.32 -7.62 0)
				(effects
					(font
						(size 1.27 1.27)
						(thickness 0.15)
					)
					(justify left bottom)
				)
			)
			(property "Voltage" "25 V"
				(at 20.32 -27.94 0)
				(effects
					(font
						(size 1.27 1.27)
					)
					(justify left bottom)
					(hide yes)
				)
			)
			(property "Dielectric" "C0G (NP0)"
				(at 20.32 -30.48 0)
				(effects
					(font
						(size 1.27 1.27)
					)
					(justify left bottom)
					(hide yes)
				)
			)
			(property "ki_keywords" "0402, SMT, CAPACITOR, PASSIVE"
				(at 0 0 0)
				(effects
					(font
						(size 1.27 1.27)
					)
					(hide yes)
				)
			)
			(symbol "C_36p_0402_0_1"
				(polyline
					(pts
						(xy 2.032 -1.524) (xy 2.032 1.524)
					)
					(stroke
						(width 0.3048)
						(type default)
					)
					(fill
						(type none)
					)
				)
				(polyline
					(pts
						(xy 3.048 -1.524) (xy 3.048 1.524)
					)
					(stroke
						(width 0.3302)
						(type default)
					)
					(fill
						(type none)
					)
				)
			)
			(symbol "C_36p_0402_1_1"
				(pin passive line
					(at 0 0 0)
					(length 2.032)
					(name "~"
						(effects
							(font
								(size 1.27 1.27)
							)
						)
					)
					(number "1"
						(effects
							(font
								(size 1.27 1.27)
							)
						)
					)
				)
				(pin passive line
					(at 5.08 0 180)
					(length 2.032)
					(name "~"
						(effects
							(font
								(size 1.27 1.27)
							)
						)
					)
					(number "2"
						(effects
							(font
								(size 1.27 1.27)
							)
						)
					)
				)
			)
		)
	(symbol "antmicroCapacitors0402:C_39p_0402"
			(pin_numbers
				(hide yes)
			)
			(pin_names
				(hide yes)
			)
			(exclude_from_sim no)
			(in_bom yes)
			(on_board yes)
			(property "Reference" "C"
				(at 20.32 -5.08 0)
				(effects
					(font
						(size 1.27 1.27)
						(thickness 0.15)
					)
					(justify left bottom)
				)
			)
			(property "Value" "C_39p_0402"
				(at 20.32 -10.16 0)
				(effects
					(font
						(size 1.27 1.27)
						(thickness 0.15)
					)
					(justify left bottom)
					(hide yes)
				)
			)
			(property "Footprint" "antmicro-footprints:C_0402_1005Metric"
				(at 20.32 -12.7 0)
				(effects
					(font
						(size 1.27 1.27)
						(thickness 0.15)
					)
					(justify left bottom)
					(hide yes)
				)
			)
			(property "Datasheet" "https://spicat.kyocera-avx.com/product/mlcc/chartview/04025A390JAT2A/"
				(at 20.32 -15.24 0)
				(effects
					(font
						(size 1.27 1.27)
						(thickness 0.15)
					)
					(justify left bottom)
					(hide yes)
				)
			)
			(property "Description" "SMD Multilayer Ceramic Capacitor, 39 pF, 50 V, 0402 [1005 Metric], ± 5%, C0G / NP0, AVX 0402 MLCC"
				(at 20.32 -33.02 0)
				(effects
					(font
						(size 1.27 1.27)
					)
					(justify left bottom)
					(hide yes)
				)
			)
			(property "MPN" "04025A390JAT2A"
				(at 20.32 -17.78 0)
				(effects
					(font
						(size 1.27 1.27)
						(thickness 0.15)
					)
					(justify left bottom)
					(hide yes)
				)
			)
			(property "Manufacturer" "KYOCERA AVX"
				(at 20.32 -20.32 0)
				(effects
					(font
						(size 1.27 1.27)
						(thickness 0.15)
					)
					(justify left bottom)
					(hide yes)
				)
			)
			(property "License" "Apache-2.0"
				(at 20.32 -22.86 0)
				(effects
					(font
						(size 1.27 1.27)
						(thickness 0.15)
					)
					(justify left bottom)
					(hide yes)
				)
			)
			(property "Author" "Antmicro"
				(at 20.32 -25.4 0)
				(effects
					(font
						(size 1.27 1.27)
						(thickness 0.15)
					)
					(justify left bottom)
					(hide yes)
				)
			)
			(property "Val" "39p"
				(at 20.32 -7.62 0)
				(effects
					(font
						(size 1.27 1.27)
						(thickness 0.15)
					)
					(justify left bottom)
				)
			)
			(property "Voltage" ""
				(at 20.32 -27.94 0)
				(effects
					(font
						(size 1.27 1.27)
					)
					(justify left bottom)
					(hide yes)
				)
			)
			(property "Dielectric" ""
				(at 20.32 -30.48 0)
				(effects
					(font
						(size 1.27 1.27)
					)
					(justify left bottom)
					(hide yes)
				)
			)
			(property "ki_keywords" "0402, SMT, CAPACITOR, PASSIVE, CERAMIC, MLCC"
				(at 0 0 0)
				(effects
					(font
						(size 1.27 1.27)
					)
					(hide yes)
				)
			)
			(symbol "C_39p_0402_0_1"
				(polyline
					(pts
						(xy 2.032 -1.524) (xy 2.032 1.524)
					)
					(stroke
						(width 0.3048)
						(type default)
					)
					(fill
						(type none)
					)
				)
				(polyline
					(pts
						(xy 3.048 -1.524) (xy 3.048 1.524)
					)
					(stroke
						(width 0.3302)
						(type default)
					)
					(fill
						(type none)
					)
				)
			)
			(symbol "C_39p_0402_1_1"
				(pin passive line
					(at 0 0 0)
					(length 2.032)
					(name "~"
						(effects
							(font
								(size 1.27 1.27)
							)
						)
					)
					(number "1"
						(effects
							(font
								(size 1.27 1.27)
							)
						)
					)
				)
				(pin passive line
					(at 5.08 0 180)
					(length 2.032)
					(name "~"
						(effects
							(font
								(size 1.27 1.27)
							)
						)
					)
					(number "2"
						(effects
							(font
								(size 1.27 1.27)
							)
						)
					)
				)
			)
		)
	(symbol "antmicroCapacitors0402:C_470p_100V_0402"
			(pin_numbers
				(hide yes)
			)
			(pin_names
				(hide yes)
			)
			(exclude_from_sim no)
			(in_bom yes)
			(on_board yes)
			(property "Reference" "C"
				(at 20.32 -5.08 0)
				(effects
					(font
						(size 1.27 1.27)
						(thickness 0.15)
					)
					(justify left bottom)
				)
			)
			(property "Value" "C_470p_100V_0402"
				(at 20.32 -10.16 0)
				(effects
					(font
						(size 1.27 1.27)
						(thickness 0.15)
					)
					(justify left bottom)
					(hide yes)
				)
			)
			(property "Footprint" "antmicro-footprints:C_0402_1005Metric"
				(at 20.32 -12.7 0)
				(effects
					(font
						(size 1.27 1.27)
						(thickness 0.15)
					)
					(justify left bottom)
					(hide yes)
				)
			)
			(property "Datasheet" "https://search.murata.co.jp/Ceramy/image/img/A01X/G101/ENG/GRM1555C2A471JE01-01A.pdf"
				(at 20.32 -15.24 0)
				(effects
					(font
						(size 1.27 1.27)
						(thickness 0.15)
					)
					(justify left bottom)
					(hide yes)
				)
			)
			(property "Description" "MLCC, SMD/SMT, 100V, 470pF, C0G/NP0, 0402 5%"
				(at 20.32 -33.02 0)
				(effects
					(font
						(size 1.27 1.27)
					)
					(justify left bottom)
					(hide yes)
				)
			)
			(property "MPN" "GRM1555C2A471JE01D"
				(at 20.32 -17.78 0)
				(effects
					(font
						(size 1.27 1.27)
						(thickness 0.15)
					)
					(justify left bottom)
					(hide yes)
				)
			)
			(property "Manufacturer" "Murata"
				(at 20.32 -20.32 0)
				(effects
					(font
						(size 1.27 1.27)
						(thickness 0.15)
					)
					(justify left bottom)
					(hide yes)
				)
			)
			(property "License" "Apache-2.0"
				(at 20.32 -22.86 0)
				(effects
					(font
						(size 1.27 1.27)
						(thickness 0.15)
					)
					(justify left bottom)
					(hide yes)
				)
			)
			(property "Author" "Antmicro"
				(at 20.32 -25.4 0)
				(effects
					(font
						(size 1.27 1.27)
						(thickness 0.15)
					)
					(justify left bottom)
					(hide yes)
				)
			)
			(property "Val" "470p"
				(at 20.32 -7.62 0)
				(effects
					(font
						(size 1.27 1.27)
						(thickness 0.15)
					)
					(justify left bottom)
				)
			)
			(property "Voltage" "100V"
				(at 20.32 -27.94 0)
				(effects
					(font
						(size 1.27 1.27)
					)
					(justify left bottom)
					(hide yes)
				)
			)
			(property "Dielectric" "C0G/NP0"
				(at 20.32 -30.48 0)
				(effects
					(font
						(size 1.27 1.27)
					)
					(justify left bottom)
					(hide yes)
				)
			)
			(property "ki_keywords" " SMT, CAPACITOR, PASSIVE"
				(at 0 0 0)
				(effects
					(font
						(size 1.27 1.27)
					)
					(hide yes)
				)
			)
			(symbol "C_470p_100V_0402_0_1"
				(polyline
					(pts
						(xy 2.032 -1.524) (xy 2.032 1.524)
					)
					(stroke
						(width 0.3048)
						(type default)
					)
					(fill
						(type none)
					)
				)
				(polyline
					(pts
						(xy 3.048 -1.524) (xy 3.048 1.524)
					)
					(stroke
						(width 0.3302)
						(type default)
					)
					(fill
						(type none)
					)
				)
			)
			(symbol "C_470p_100V_0402_1_1"
				(pin passive line
					(at 0 0 0)
					(length 2.032)
					(name "~"
						(effects
							(font
								(size 1.27 1.27)
							)
						)
					)
					(number "1"
						(effects
							(font
								(size 1.27 1.27)
							)
						)
					)
				)
				(pin passive line
					(at 5.08 0 180)
					(length 2.032)
					(name "~"
						(effects
							(font
								(size 1.27 1.27)
							)
						)
					)
					(number "2"
						(effects
							(font
								(size 1.27 1.27)
							)
						)
					)
				)
			)
		)
	(symbol "antmicroCapacitors0402:C_4u7_0402"
			(pin_numbers
				(hide yes)
			)
			(pin_names
				(hide yes)
			)
			(exclude_from_sim no)
			(in_bom yes)
			(on_board yes)
			(property "Reference" "C"
				(at 20.32 -5.08 0)
				(effects
					(font
						(size 1.27 1.27)
						(thickness 0.15)
					)
					(justify left bottom)
				)
			)
			(property "Value" "C_4u7_0402"
				(at 20.32 -10.16 0)
				(effects
					(font
						(size 1.27 1.27)
						(thickness 0.15)
					)
					(justify left bottom)
					(hide yes)
				)
			)
			(property "Footprint" "antmicro-footprints:C_0402_1005Metric"
				(at 20.32 -12.7 0)
				(effects
					(font
						(size 1.27 1.27)
						(thickness 0.15)
					)
					(justify left bottom)
					(hide yes)
				)
			)
			(property "Datasheet" "https://www.murata.com/products/productdetail?partno=GRM155R61A475MEAA%23"
				(at 20.32 -15.24 0)
				(effects
					(font
						(size 1.27 1.27)
						(thickness 0.15)
					)
					(justify left bottom)
					(hide yes)
				)
			)
			(property "Description" "SMD Multilayer Ceramic Capacitor, 4.7 µF, 10 V, 0402 [1005 Metric], ± 20%, X5R, GRM Series"
				(at 0 0 0)
				(effects
					(font
						(size 1.27 1.27)
					)
					(hide yes)
				)
			)
			(property "MPN" "GRM155R61A475MEAAD"
				(at 20.32 -17.78 0)
				(effects
					(font
						(size 1.27 1.27)
						(thickness 0.15)
					)
					(justify left bottom)
					(hide yes)
				)
			)
			(property "Manufacturer" "Murata"
				(at 20.32 -20.32 0)
				(effects
					(font
						(size 1.27 1.27)
						(thickness 0.15)
					)
					(justify left bottom)
					(hide yes)
				)
			)
			(property "License" "Apache-2.0"
				(at 20.32 -22.86 0)
				(effects
					(font
						(size 1.27 1.27)
						(thickness 0.15)
					)
					(justify left bottom)
					(hide yes)
				)
			)
			(property "Author" "Antmicro"
				(at 20.32 -25.4 0)
				(effects
					(font
						(size 1.27 1.27)
						(thickness 0.15)
					)
					(justify left bottom)
					(hide yes)
				)
			)
			(property "Val" "4u7"
				(at 20.32 -7.62 0)
				(effects
					(font
						(size 1.27 1.27)
						(thickness 0.15)
					)
					(justify left bottom)
				)
			)
			(property "Voltage" ""
				(at 20.32 -27.94 0)
				(effects
					(font
						(size 1.27 1.27)
					)
					(justify left bottom)
					(hide yes)
				)
			)
			(property "Dielectric" ""
				(at 20.32 -30.48 0)
				(effects
					(font
						(size 1.27 1.27)
					)
					(justify left bottom)
					(hide yes)
				)
			)
			(property "ki_keywords" "0402, SMT, CAPACITOR, PASSIVE"
				(at 0 0 0)
				(effects
					(font
						(size 1.27 1.27)
					)
					(hide yes)
				)
			)
			(symbol "C_4u7_0402_0_1"
				(polyline
					(pts
						(xy 2.032 -1.524) (xy 2.032 1.524)
					)
					(stroke
						(width 0.3048)
						(type default)
					)
					(fill
						(type none)
					)
				)
				(polyline
					(pts
						(xy 3.048 -1.524) (xy 3.048 1.524)
					)
					(stroke
						(width 0.3302)
						(type default)
					)
					(fill
						(type none)
					)
				)
			)
			(symbol "C_4u7_0402_1_1"
				(pin passive line
					(at 0 0 0)
					(length 2.032)
					(name "~"
						(effects
							(font
								(size 1.27 1.27)
							)
						)
					)
					(number "1"
						(effects
							(font
								(size 1.27 1.27)
							)
						)
					)
				)
				(pin passive line
					(at 5.08 0 180)
					(length 2.032)
					(name "~"
						(effects
							(font
								(size 1.27 1.27)
							)
						)
					)
					(number "2"
						(effects
							(font
								(size 1.27 1.27)
							)
						)
					)
				)
			)
		)
	(symbol "antmicroCapacitors0402:C_template_name_0402"
			(pin_numbers
				(hide yes)
			)
			(pin_names
				(hide yes)
			)
			(exclude_from_sim no)
			(in_bom yes)
			(on_board yes)
			(property "Reference" "C"
				(at 20.32 -5.08 0)
				(effects
					(font
						(size 1.27 1.27)
						(thickness 0.15)
					)
					(justify left bottom)
				)
			)
			(property "Value" "C_template_name_0402"
				(at 20.32 -10.16 0)
				(effects
					(font
						(size 1.27 1.27)
						(thickness 0.15)
					)
					(justify left bottom)
					(hide yes)
				)
			)
			(property "Footprint" "antmicro-footprints:C_0402_1005Metric"
				(at 20.32 -12.7 0)
				(effects
					(font
						(size 1.27 1.27)
						(thickness 0.15)
					)
					(justify left bottom)
					(hide yes)
				)
			)
			(property "Datasheet" "template_datasheet"
				(at 20.32 -15.24 0)
				(effects
					(font
						(size 1.27 1.27)
						(thickness 0.15)
					)
					(justify left bottom)
					(hide yes)
				)
			)
			(property "Description" "template_value capacitor in 0402 package with template_voltage max voltage and template_dielectric dielectric"
				(at 0 0 0)
				(effects
					(font
						(size 1.27 1.27)
					)
					(hide yes)
				)
			)
			(property "MPN" "template_MPN"
				(at 20.32 -17.78 0)
				(effects
					(font
						(size 1.27 1.27)
						(thickness 0.15)
					)
					(justify left bottom)
					(hide yes)
				)
			)
			(property "Manufacturer" "template_manufacturer"
				(at 20.32 -20.32 0)
				(effects
					(font
						(size 1.27 1.27)
						(thickness 0.15)
					)
					(justify left bottom)
					(hide yes)
				)
			)
			(property "License" "Apache-2.0"
				(at 20.32 -22.86 0)
				(effects
					(font
						(size 1.27 1.27)
						(thickness 0.15)
					)
					(justify left bottom)
					(hide yes)
				)
			)
			(property "Author" "Antmicro"
				(at 20.32 -25.4 0)
				(effects
					(font
						(size 1.27 1.27)
						(thickness 0.15)
					)
					(justify left bottom)
					(hide yes)
				)
			)
			(property "Val" "template_value"
				(at 20.32 -7.62 0)
				(effects
					(font
						(size 1.27 1.27)
						(thickness 0.15)
					)
					(justify left bottom)
				)
			)
			(property "Voltage" "template_voltage"
				(at 20.32 -27.94 0)
				(effects
					(font
						(size 1.27 1.27)
					)
					(justify left bottom)
					(hide yes)
				)
			)
			(property "Dielectric" "template_dielectric"
				(at 20.32 -30.48 0)
				(effects
					(font
						(size 1.27 1.27)
					)
					(justify left bottom)
					(hide yes)
				)
			)
			(symbol "C_template_name_0402_0_1"
				(polyline
					(pts
						(xy 2.032 -1.524) (xy 2.032 1.524)
					)
					(stroke
						(width 0.3048)
						(type default)
					)
					(fill
						(type none)
					)
				)
				(polyline
					(pts
						(xy 3.048 -1.524) (xy 3.048 1.524)
					)
					(stroke
						(width 0.3302)
						(type default)
					)
					(fill
						(type none)
					)
				)
			)
			(symbol "C_template_name_0402_1_1"
				(pin passive line
					(at 0 0 0)
					(length 2.032)
					(name "~"
						(effects
							(font
								(size 1.27 1.27)
							)
						)
					)
					(number "1"
						(effects
							(font
								(size 1.27 1.27)
							)
						)
					)
				)
				(pin passive line
					(at 5.08 0 180)
					(length 2.032)
					(name "~"
						(effects
							(font
								(size 1.27 1.27)
							)
						)
					)
					(number "2"
						(effects
							(font
								(size 1.27 1.27)
							)
						)
					)
				)
			)
		)
	(symbol "antmicroCapacitorsmisc:C_100n_100V_0805"
			(pin_numbers
				(hide yes)
			)
			(pin_names
				(hide yes)
			)
			(exclude_from_sim no)
			(in_bom yes)
			(on_board yes)
			(property "Reference" "C"
				(at 20.32 -5.08 0)
				(effects
					(font
						(size 1.27 1.27)
						(thickness 0.15)
					)
					(justify left bottom)
				)
			)
			(property "Value" "C_100n_100V_0805"
				(at 20.32 -10.16 0)
				(effects
					(font
						(size 1.27 1.27)
						(thickness 0.15)
					)
					(justify left bottom)
					(hide yes)
				)
			)
			(property "Footprint" "antmicro-footprints:C_0805_2012Metric"
				(at 20.32 -12.7 0)
				(effects
					(font
						(size 1.27 1.27)
						(thickness 0.15)
					)
					(justify left bottom)
					(hide yes)
				)
			)
			(property "Datasheet" "https://product.samsungsem.com/mlcc/CL21B104KCFNNN.do"
				(at 20.32 -15.24 0)
				(effects
					(font
						(size 1.27 1.27)
						(thickness 0.15)
					)
					(justify left bottom)
					(hide yes)
				)
			)
			(property "Description" "SMT Multilayer Ceramic Capacitor, 0.1 µF, 100 V, 0805 [2012 Metric], ± 10%, X7R, CL"
				(at 0 0 0)
				(effects
					(font
						(size 1.27 1.27)
					)
					(hide yes)
				)
			)
			(property "MPN" "CL21B104KCFNNNE"
				(at 20.32 -17.78 0)
				(effects
					(font
						(size 1.27 1.27)
						(thickness 0.15)
					)
					(justify left bottom)
					(hide yes)
				)
			)
			(property "Manufacturer" "Samsung Electro-Mechanics"
				(at 20.32 -20.32 0)
				(effects
					(font
						(size 1.27 1.27)
						(thickness 0.15)
					)
					(justify left bottom)
					(hide yes)
				)
			)
			(property "License" "Apache-2.0"
				(at 20.32 -22.86 0)
				(effects
					(font
						(size 1.27 1.27)
						(thickness 0.15)
					)
					(justify left bottom)
					(hide yes)
				)
			)
			(property "Author" "Antmicro"
				(at 20.32 -25.4 0)
				(effects
					(font
						(size 1.27 1.27)
						(thickness 0.15)
					)
					(justify left bottom)
					(hide yes)
				)
			)
			(property "Val" "100n"
				(at 20.32 -7.62 0)
				(effects
					(font
						(size 1.27 1.27)
						(thickness 0.15)
					)
					(justify left bottom)
				)
			)
			(property "Voltage" "100V"
				(at 20.32 -27.94 0)
				(effects
					(font
						(size 1.27 1.27)
					)
					(justify left bottom)
				)
			)
			(property "Dielectric" "X7R"
				(at 20.32 -30.48 0)
				(effects
					(font
						(size 1.27 1.27)
					)
					(justify left bottom)
					(hide yes)
				)
			)
			(property "Public" "False"
				(at 20.32 -33.02 0)
				(effects
					(font
						(size 1.27 1.27)
					)
					(justify left bottom)
					(hide yes)
				)
			)
			(property "ki_keywords" "0805, SMT, CAPACITOR, PASSIVE"
				(at 0 0 0)
				(effects
					(font
						(size 1.27 1.27)
					)
					(hide yes)
				)
			)
			(symbol "C_100n_100V_0805_0_1"
				(polyline
					(pts
						(xy 2.032 -1.524) (xy 2.032 1.524)
					)
					(stroke
						(width 0.3048)
						(type default)
					)
					(fill
						(type none)
					)
				)
				(polyline
					(pts
						(xy 3.048 -1.524) (xy 3.048 1.524)
					)
					(stroke
						(width 0.3302)
						(type default)
					)
					(fill
						(type none)
					)
				)
			)
			(symbol "C_100n_100V_0805_1_1"
				(pin passive line
					(at 0 0 0)
					(length 2.032)
					(name "~"
						(effects
							(font
								(size 1.27 1.27)
							)
						)
					)
					(number "1"
						(effects
							(font
								(size 1.27 1.27)
							)
						)
					)
				)
				(pin passive line
					(at 5.08 0 180)
					(length 2.032)
					(name "~"
						(effects
							(font
								(size 1.27 1.27)
							)
						)
					)
					(number "2"
						(effects
							(font
								(size 1.27 1.27)
							)
						)
					)
				)
			)
		)
	(symbol "antmicroCapacitorsmisc:C_22u_100V_2220"
			(pin_numbers
				(hide yes)
			)
			(pin_names
				(hide yes)
			)
			(exclude_from_sim no)
			(in_bom yes)
			(on_board yes)
			(property "Reference" "C"
				(at 20.32 -5.08 0)
				(effects
					(font
						(size 1.27 1.27)
						(thickness 0.15)
					)
					(justify left bottom)
				)
			)
			(property "Value" "C_22u_100V_2220"
				(at 20.32 -10.16 0)
				(effects
					(font
						(size 1.27 1.27)
						(thickness 0.15)
					)
					(justify left bottom)
					(hide yes)
				)
			)
			(property "Footprint" "antmicro-footprints:C_2220_5650Metric"
				(at 20.32 -12.7 0)
				(effects
					(font
						(size 1.27 1.27)
						(thickness 0.15)
					)
					(justify left bottom)
					(hide yes)
				)
			)
			(property "Datasheet" "https://product.tdk.com/en/search/capacitor/ceramic/mlcc/info?part_no=C5750X7S2A226M280KB"
				(at 20.32 -15.24 0)
				(effects
					(font
						(size 1.27 1.27)
						(thickness 0.15)
					)
					(justify left bottom)
					(hide yes)
				)
			)
			(property "Description" "SMT Multilayer Ceramic Capacitor, 22 µF, 100 V, 2220 [5750 Metric], ± 20%, X7S, C"
				(at 0 0 0)
				(effects
					(font
						(size 1.27 1.27)
					)
					(hide yes)
				)
			)
			(property "MPN" "C5750X7S2A226M280KB"
				(at 20.32 -17.78 0)
				(effects
					(font
						(size 1.27 1.27)
						(thickness 0.15)
					)
					(justify left bottom)
					(hide yes)
				)
			)
			(property "Manufacturer" "TDK"
				(at 20.32 -20.32 0)
				(effects
					(font
						(size 1.27 1.27)
						(thickness 0.15)
					)
					(justify left bottom)
					(hide yes)
				)
			)
			(property "License" "Apache-2.0"
				(at 20.32 -22.86 0)
				(effects
					(font
						(size 1.27 1.27)
						(thickness 0.15)
					)
					(justify left bottom)
					(hide yes)
				)
			)
			(property "Author" "Antmicro"
				(at 20.32 -25.4 0)
				(effects
					(font
						(size 1.27 1.27)
						(thickness 0.15)
					)
					(justify left bottom)
					(hide yes)
				)
			)
			(property "Val" "22u"
				(at 20.32 -7.62 0)
				(effects
					(font
						(size 1.27 1.27)
						(thickness 0.15)
					)
					(justify left bottom)
				)
			)
			(property "Voltage" "100V"
				(at 20.32 -27.94 0)
				(effects
					(font
						(size 1.27 1.27)
					)
					(justify left bottom)
				)
			)
			(property "Dielectric" "X7S"
				(at 20.32 -30.48 0)
				(effects
					(font
						(size 1.27 1.27)
					)
					(justify left bottom)
					(hide yes)
				)
			)
			(property "Public" "False"
				(at 20.32 -33.02 0)
				(effects
					(font
						(size 1.27 1.27)
					)
					(justify left bottom)
					(hide yes)
				)
			)
			(property "ki_keywords" "SMT, CAPACITOR, PASSIVE"
				(at 0 0 0)
				(effects
					(font
						(size 1.27 1.27)
					)
					(hide yes)
				)
			)
			(symbol "C_22u_100V_2220_0_1"
				(polyline
					(pts
						(xy 2.032 -1.524) (xy 2.032 1.524)
					)
					(stroke
						(width 0.3048)
						(type default)
					)
					(fill
						(type none)
					)
				)
				(polyline
					(pts
						(xy 3.048 -1.524) (xy 3.048 1.524)
					)
					(stroke
						(width 0.3302)
						(type default)
					)
					(fill
						(type none)
					)
				)
			)
			(symbol "C_22u_100V_2220_1_1"
				(pin passive line
					(at 0 0 0)
					(length 2.032)
					(name "~"
						(effects
							(font
								(size 1.27 1.27)
							)
						)
					)
					(number "1"
						(effects
							(font
								(size 1.27 1.27)
							)
						)
					)
				)
				(pin passive line
					(at 5.08 0 180)
					(length 2.032)
					(name "~"
						(effects
							(font
								(size 1.27 1.27)
							)
						)
					)
					(number "2"
						(effects
							(font
								(size 1.27 1.27)
							)
						)
					)
				)
			)
		)
	(symbol "antmicroCapacitorsmisc:C_22u_25V_0805"
			(pin_numbers
				(hide yes)
			)
			(pin_names
				(hide yes)
			)
			(exclude_from_sim no)
			(in_bom yes)
			(on_board yes)
			(property "Reference" "C"
				(at 20.32 -5.08 0)
				(effects
					(font
						(size 1.27 1.27)
						(thickness 0.15)
					)
					(justify left bottom)
				)
			)
			(property "Value" "C_22u_25V_0805"
				(at 20.32 -10.16 0)
				(effects
					(font
						(size 1.27 1.27)
						(thickness 0.15)
					)
					(justify left bottom)
					(hide yes)
				)
			)
			(property "Footprint" "antmicro-footprints:C_0805_2012Metric"
				(at 20.32 -12.7 0)
				(effects
					(font
						(size 1.27 1.27)
						(thickness 0.15)
					)
					(justify left bottom)
					(hide yes)
				)
			)
			(property "Datasheet" "https://product.samsungsem.com/mlcc/CL21A226MAYNNN.do"
				(at 20.32 -15.24 0)
				(effects
					(font
						(size 1.27 1.27)
						(thickness 0.15)
					)
					(justify left bottom)
					(hide yes)
				)
			)
			(property "Description" "SMT Multilayer Ceramic Capacitor, 22uF, +/-20%, 25V, X5R, 0805 [2012 Metric]"
				(at 0 0 0)
				(effects
					(font
						(size 1.27 1.27)
					)
					(hide yes)
				)
			)
			(property "MPN" "CL21A226MAYNNNE"
				(at 20.32 -17.78 0)
				(effects
					(font
						(size 1.27 1.27)
						(thickness 0.15)
					)
					(justify left bottom)
					(hide yes)
				)
			)
			(property "Manufacturer" "Samsung Electro-Mechanics"
				(at 20.32 -20.32 0)
				(effects
					(font
						(size 1.27 1.27)
						(thickness 0.15)
					)
					(justify left bottom)
					(hide yes)
				)
			)
			(property "License" "Apache-2.0"
				(at 20.32 -22.86 0)
				(effects
					(font
						(size 1.27 1.27)
						(thickness 0.15)
					)
					(justify left bottom)
					(hide yes)
				)
			)
			(property "Author" "Antmicro"
				(at 20.32 -25.4 0)
				(effects
					(font
						(size 1.27 1.27)
						(thickness 0.15)
					)
					(justify left bottom)
					(hide yes)
				)
			)
			(property "Val" "22u"
				(at 20.32 -7.62 0)
				(effects
					(font
						(size 1.27 1.27)
						(thickness 0.15)
					)
					(justify left bottom)
				)
			)
			(property "Voltage" "25V"
				(at 20.32 -27.94 0)
				(effects
					(font
						(size 1.27 1.27)
					)
					(justify left bottom)
				)
			)
			(property "Dielectric" "X5R"
				(at 20.32 -30.48 0)
				(effects
					(font
						(size 1.27 1.27)
					)
					(justify left bottom)
					(hide yes)
				)
			)
			(property "Public" "False"
				(at 20.32 -33.02 0)
				(effects
					(font
						(size 1.27 1.27)
					)
					(justify left bottom)
					(hide yes)
				)
			)
			(property "ki_keywords" "0805, SMT, CAPACITOR, PASSIVE"
				(at 0 0 0)
				(effects
					(font
						(size 1.27 1.27)
					)
					(hide yes)
				)
			)
			(symbol "C_22u_25V_0805_0_1"
				(polyline
					(pts
						(xy 2.032 -1.524) (xy 2.032 1.524)
					)
					(stroke
						(width 0.3048)
						(type default)
					)
					(fill
						(type none)
					)
				)
				(polyline
					(pts
						(xy 3.048 -1.524) (xy 3.048 1.524)
					)
					(stroke
						(width 0.3302)
						(type default)
					)
					(fill
						(type none)
					)
				)
			)
			(symbol "C_22u_25V_0805_1_1"
				(pin passive line
					(at 0 0 0)
					(length 2.032)
					(name "~"
						(effects
							(font
								(size 1.27 1.27)
							)
						)
					)
					(number "1"
						(effects
							(font
								(size 1.27 1.27)
							)
						)
					)
				)
				(pin passive line
					(at 5.08 0 180)
					(length 2.032)
					(name "~"
						(effects
							(font
								(size 1.27 1.27)
							)
						)
					)
					(number "2"
						(effects
							(font
								(size 1.27 1.27)
							)
						)
					)
				)
			)
		)
	(symbol "antmicroCapacitorspol:C_Pol_330u_6.3V_KEMET-T520-B"
			(pin_numbers
				(hide yes)
			)
			(pin_names
				(hide yes)
			)
			(exclude_from_sim no)
			(in_bom yes)
			(on_board yes)
			(property "Reference" "C"
				(at 13.97 0 0)
				(effects
					(font
						(size 1.27 1.27)
						(thickness 0.15)
					)
					(justify left bottom)
				)
			)
			(property "Value" "C_Pol_330u_6.3V_KEMET-T520-B"
				(at 13.97 -2.54 0)
				(effects
					(font
						(size 1.27 1.27)
						(thickness 0.15)
					)
					(justify left bottom)
					(hide yes)
				)
			)
			(property "Footprint" "antmicro-footprints:C_Pol_EIA-B"
				(at 13.97 -7.62 0)
				(effects
					(font
						(size 1.27 1.27)
						(thickness 0.15)
					)
					(justify left bottom)
					(hide yes)
				)
			)
			(property "Datasheet" "https://www.kemet.com/en/us/capacitors/product/T520B337M006ATE040.html"
				(at 13.97 -10.16 0)
				(effects
					(font
						(size 1.27 1.27)
						(thickness 0.15)
					)
					(justify left bottom)
					(hide yes)
				)
			)
			(property "Description" "Tantalum Polymer Capacitor, KO-CAP®, 330 µF, ± 20%, 6.3 V, B, 0.04 ohm, 1411 [3528 Metric]"
				(at 0 0 0)
				(effects
					(font
						(size 1.27 1.27)
					)
					(hide yes)
				)
			)
			(property "Val" "330u"
				(at 13.97 -5.08 0)
				(effects
					(font
						(size 1.27 1.27)
						(thickness 0.15)
					)
					(justify left bottom)
				)
			)
			(property "MPN" "T520B337M006ATE040"
				(at 13.97 -12.7 0)
				(effects
					(font
						(size 1.27 1.27)
						(thickness 0.15)
					)
					(justify left bottom)
					(hide yes)
				)
			)
			(property "Manufacturer" "KEMET"
				(at 13.97 -15.24 0)
				(effects
					(font
						(size 1.27 1.27)
						(thickness 0.15)
					)
					(justify left bottom)
					(hide yes)
				)
			)
			(property "License" "Apache-2.0"
				(at 13.97 -17.78 0)
				(effects
					(font
						(size 1.27 1.27)
						(thickness 0.15)
					)
					(justify left bottom)
					(hide yes)
				)
			)
			(property "Author" "Antmicro"
				(at 13.97 -20.32 0)
				(effects
					(font
						(size 1.27 1.27)
						(thickness 0.15)
					)
					(justify left bottom)
					(hide yes)
				)
			)
			(property "Voltage" "6.3V"
				(at 13.97 -22.86 0)
				(effects
					(font
						(size 1.27 1.27)
					)
					(justify left bottom)
					(hide yes)
				)
			)
			(property "Dielectric" "template_dielectric"
				(at 13.97 -25.4 0)
				(effects
					(font
						(size 1.27 1.27)
					)
					(justify left bottom)
					(hide yes)
				)
			)
			(property "ki_keywords" "SMT, CAPACITOR, PASSIVE, POLARIZED, TANTALUM"
				(at 0 0 0)
				(effects
					(font
						(size 1.27 1.27)
					)
					(hide yes)
				)
			)
			(symbol "C_Pol_330u_6.3V_KEMET-T520-B_0_1"
				(polyline
					(pts
						(xy 0.9652 1.27) (xy 0.9652 1.778)
					)
					(stroke
						(width 0)
						(type default)
					)
					(fill
						(type none)
					)
				)
				(polyline
					(pts
						(xy 1.2192 1.524) (xy 0.7112 1.524)
					)
					(stroke
						(width 0)
						(type default)
					)
					(fill
						(type none)
					)
				)
				(rectangle
					(start 1.905 -1.524)
					(end 2.286 1.524)
					(stroke
						(width 0)
						(type default)
					)
					(fill
						(type none)
					)
				)
				(rectangle
					(start 2.921 -1.524)
					(end 3.302 1.524)
					(stroke
						(width 0)
						(type default)
					)
					(fill
						(type outline)
					)
				)
			)
			(symbol "C_Pol_330u_6.3V_KEMET-T520-B_1_1"
				(pin passive line
					(at 0 0 0)
					(length 1.8542)
					(name "~"
						(effects
							(font
								(size 1.27 1.27)
							)
						)
					)
					(number "1"
						(effects
							(font
								(size 1.27 1.27)
							)
						)
					)
				)
				(pin passive line
					(at 5.08 0 180)
					(length 1.8542)
					(name "~"
						(effects
							(font
								(size 1.27 1.27)
							)
						)
					)
					(number "2"
						(effects
							(font
								(size 1.27 1.27)
							)
						)
					)
				)
			)
		)
	(symbol "antmicroClockTimingRealTimeClocks:DS1338_SOIC"
			(exclude_from_sim no)
			(in_bom yes)
			(on_board yes)
			(property "Reference" "U"
				(at 33.02 -5.08 0)
				(effects
					(font
						(size 1.27 1.27)
						(thickness 0.15)
					)
					(justify left bottom)
				)
			)
			(property "Value" "DS1338_SOIC"
				(at 33.02 -12.7 0)
				(effects
					(font
						(size 1.27 1.27)
						(thickness 0.15)
					)
					(justify left bottom)
					(hide yes)
				)
			)
			(property "Footprint" "antmicro-footprints:SOIC-8_3.9x4.9x1.75mm_P1.27mm"
				(at 33.02 -15.24 0)
				(effects
					(font
						(size 1.27 1.27)
						(thickness 0.15)
					)
					(justify left bottom)
					(hide yes)
				)
			)
			(property "Datasheet" "https://www.analog.com/media/en/technical-documentation/data-sheets/DS1338-DS1338Z.pdf"
				(at 33.02 -17.78 0)
				(effects
					(font
						(size 1.27 1.27)
						(thickness 0.15)
					)
					(justify left bottom)
					(hide yes)
				)
			)
			(property "Description" "Real-time clock/calendar,  1.71V-5.5V supply, I2C, SOIC-8"
				(at 33.02 -25.4 0)
				(effects
					(font
						(size 1.27 1.27)
					)
					(justify left bottom)
					(hide yes)
				)
			)
			(property "MPN" "DS1338Z-18+"
				(at 33.02 -7.62 0)
				(effects
					(font
						(size 1.27 1.27)
						(thickness 0.15)
					)
					(justify left bottom)
				)
			)
			(property "Manufacturer" "Maxim Integrated Products"
				(at 33.02 -10.16 0)
				(effects
					(font
						(size 1.27 1.27)
						(thickness 0.15)
					)
					(justify left bottom)
					(hide yes)
				)
			)
			(property "Author" "Antmicro"
				(at 33.02 -20.32 0)
				(effects
					(font
						(size 1.27 1.27)
						(thickness 0.15)
					)
					(justify left bottom)
					(hide yes)
				)
			)
			(property "License" "Apache-2.0"
				(at 33.02 -22.86 0)
				(effects
					(font
						(size 1.27 1.27)
						(thickness 0.15)
					)
					(justify left bottom)
					(hide yes)
				)
			)
			(property "ki_keywords" "SMT, IC, CLOCK"
				(at 0 0 0)
				(effects
					(font
						(size 1.27 1.27)
					)
					(hide yes)
				)
			)
			(symbol "DS1338_SOIC_1_1"
				(rectangle
					(start 2.54 2.54)
					(end 17.78 -12.7)
					(stroke
						(width 0.254)
						(type default)
					)
					(fill
						(type background)
					)
				)
				(pin power_in line
					(at 0 0 0)
					(length 2.54)
					(name "V_{CC}"
						(effects
							(font
								(size 1.27 1.27)
							)
						)
					)
					(number "8"
						(effects
							(font
								(size 1.27 1.27)
							)
						)
					)
				)
				(pin bidirectional line
					(at 0 -2.54 0)
					(length 2.54)
					(name "SDA"
						(effects
							(font
								(size 1.27 1.27)
							)
						)
					)
					(number "5"
						(effects
							(font
								(size 1.27 1.27)
							)
						)
					)
				)
				(pin input line
					(at 0 -5.08 0)
					(length 2.54)
					(name "SCL"
						(effects
							(font
								(size 1.27 1.27)
							)
						)
					)
					(number "6"
						(effects
							(font
								(size 1.27 1.27)
							)
						)
					)
				)
				(pin power_in line
					(at 0 -10.16 0)
					(length 2.54)
					(name "GND"
						(effects
							(font
								(size 1.27 1.27)
							)
						)
					)
					(number "4"
						(effects
							(font
								(size 1.27 1.27)
							)
						)
					)
				)
				(pin power_in line
					(at 20.32 0 180)
					(length 2.54)
					(name "V_{bat}"
						(effects
							(font
								(size 1.27 1.27)
							)
						)
					)
					(number "3"
						(effects
							(font
								(size 1.27 1.27)
							)
						)
					)
				)
				(pin output line
					(at 20.32 -2.54 180)
					(length 2.54)
					(name "SQW/OUT"
						(effects
							(font
								(size 1.27 1.27)
							)
						)
					)
					(number "7"
						(effects
							(font
								(size 1.27 1.27)
							)
						)
					)
				)
				(pin input line
					(at 20.32 -7.62 180)
					(length 2.54)
					(name "X1"
						(effects
							(font
								(size 1.27 1.27)
							)
						)
					)
					(number "1"
						(effects
							(font
								(size 1.27 1.27)
							)
						)
					)
				)
				(pin output line
					(at 20.32 -10.16 180)
					(length 2.54)
					(name "X2"
						(effects
							(font
								(size 1.27 1.27)
							)
						)
					)
					(number "2"
						(effects
							(font
								(size 1.27 1.27)
							)
						)
					)
				)
			)
		)
	(symbol "antmicroCommonModeChokes:Choke_DLW21SN900SQ2L"
			(pin_names
				(hide yes)
			)
			(exclude_from_sim no)
			(in_bom yes)
			(on_board yes)
			(property "Reference" "T"
				(at 15.24 -5.08 0)
				(effects
					(font
						(size 1.27 1.27)
						(thickness 0.15)
					)
					(justify left bottom)
				)
			)
			(property "Value" "Choke_DLW21SN900SQ2L"
				(at 15.24 -10.16 0)
				(effects
					(font
						(size 1.27 1.27)
						(thickness 0.15)
					)
					(justify left bottom)
					(hide yes)
				)
			)
			(property "Footprint" "antmicro-footprints:Choke_Murata-DLW21"
				(at 15.24 -12.7 0)
				(effects
					(font
						(size 1.27 1.27)
						(thickness 0.15)
					)
					(justify left bottom)
					(hide yes)
				)
			)
			(property "Datasheet" "https://www.murata.com/en-us/products/productdetail?partno=DLW21SN900SQ2%23"
				(at 15.24 -15.24 0)
				(effects
					(font
						(size 1.27 1.27)
						(thickness 0.15)
					)
					(justify left bottom)
					(hide yes)
				)
			)
			(property "Description" "Choke, Common Mode, DLW21S Series, 90 ohm, 330 mA, 0805, 2mm x 1.2mm x 1.2mm"
				(at 0 0 0)
				(effects
					(font
						(size 1.27 1.27)
					)
					(hide yes)
				)
			)
			(property "Manufacturer" "Murata"
				(at 15.24 -17.78 0)
				(effects
					(font
						(size 1.27 1.27)
						(thickness 0.15)
					)
					(justify left bottom)
					(hide yes)
				)
			)
			(property "MPN" "DLW21SN900SQ2L"
				(at 15.24 -7.62 0)
				(effects
					(font
						(size 1.27 1.27)
						(thickness 0.15)
					)
					(justify left bottom)
				)
			)
			(property "IMax" "0.33 A"
				(at 15.24 -20.32 0)
				(effects
					(font
						(size 1.27 1.27)
						(thickness 0.15)
					)
					(justify left bottom)
					(hide yes)
				)
			)
			(property "Author" "Antmicro"
				(at 15.24 -22.86 0)
				(effects
					(font
						(size 1.27 1.27)
						(thickness 0.15)
					)
					(justify left bottom)
					(hide yes)
				)
			)
			(property "License" "Apache-2.0"
				(at 15.24 -25.4 0)
				(effects
					(font
						(size 1.27 1.27)
						(thickness 0.15)
					)
					(justify left bottom)
					(hide yes)
				)
			)
			(property "ki_keywords" "CHOKE, PASSIVE"
				(at 0 0 0)
				(effects
					(font
						(size 1.27 1.27)
					)
					(hide yes)
				)
			)
			(property "ki_fp_filters" "IND_ACM9070_TDK"
				(at 0 0 0)
				(effects
					(font
						(size 1.27 1.27)
					)
					(hide yes)
				)
			)
			(symbol "Choke_DLW21SN900SQ2L_1_1"
				(circle
					(center 2.032 -1.016)
					(radius 0.254)
					(stroke
						(width 0.254)
						(type default)
					)
					(fill
						(type outline)
					)
				)
				(circle
					(center 2.032 -3.81)
					(radius 0.254)
					(stroke
						(width 0.254)
						(type default)
					)
					(fill
						(type outline)
					)
				)
				(polyline
					(pts
						(xy 2.54 -0.508) (xy 2.54 0)
					)
					(stroke
						(width 0)
						(type default)
					)
					(fill
						(type none)
					)
				)
				(polyline
					(pts
						(xy 2.54 -2.032) (xy 7.62 -2.032)
					)
					(stroke
						(width 0.254)
						(type default)
					)
					(fill
						(type none)
					)
				)
				(polyline
					(pts
						(xy 2.54 -4.572) (xy 2.54 -5.08)
					)
					(stroke
						(width 0)
						(type default)
					)
					(fill
						(type none)
					)
				)
				(arc
					(start 3.556 -0.508)
					(mid 3.048 -1.0138)
					(end 2.54 -0.508)
					(stroke
						(width 0)
						(type default)
					)
					(fill
						(type none)
					)
				)
				(arc
					(start 2.54 -4.572)
					(mid 3.048 -4.0662)
					(end 3.556 -4.572)
					(stroke
						(width 0)
						(type default)
					)
					(fill
						(type none)
					)
				)
				(arc
					(start 4.572 -0.508)
					(mid 4.064 -1.0138)
					(end 3.556 -0.508)
					(stroke
						(width 0)
						(type default)
					)
					(fill
						(type none)
					)
				)
				(arc
					(start 3.556 -4.572)
					(mid 4.064 -4.0662)
					(end 4.572 -4.572)
					(stroke
						(width 0)
						(type default)
					)
					(fill
						(type none)
					)
				)
				(arc
					(start 5.588 -0.508)
					(mid 5.08 -1.0138)
					(end 4.572 -0.508)
					(stroke
						(width 0)
						(type default)
					)
					(fill
						(type none)
					)
				)
				(arc
					(start 4.572 -4.572)
					(mid 5.08 -4.0662)
					(end 5.588 -4.572)
					(stroke
						(width 0)
						(type default)
					)
					(fill
						(type none)
					)
				)
				(arc
					(start 6.604 -0.508)
					(mid 6.096 -1.0138)
					(end 5.588 -0.508)
					(stroke
						(width 0)
						(type default)
					)
					(fill
						(type none)
					)
				)
				(arc
					(start 5.588 -4.572)
					(mid 6.096 -4.0662)
					(end 6.604 -4.572)
					(stroke
						(width 0)
						(type default)
					)
					(fill
						(type none)
					)
				)
				(arc
					(start 7.62 -0.508)
					(mid 7.112 -1.0138)
					(end 6.604 -0.508)
					(stroke
						(width 0)
						(type default)
					)
					(fill
						(type none)
					)
				)
				(arc
					(start 6.604 -4.572)
					(mid 7.112 -4.0662)
					(end 7.62 -4.572)
					(stroke
						(width 0)
						(type default)
					)
					(fill
						(type none)
					)
				)
				(polyline
					(pts
						(xy 7.62 0) (xy 7.62 -0.508)
					)
					(stroke
						(width 0)
						(type default)
					)
					(fill
						(type none)
					)
				)
				(polyline
					(pts
						(xy 7.62 -3.048) (xy 2.54 -3.048)
					)
					(stroke
						(width 0.254)
						(type default)
					)
					(fill
						(type none)
					)
				)
				(polyline
					(pts
						(xy 7.62 -4.572) (xy 7.62 -5.08)
					)
					(stroke
						(width 0)
						(type default)
					)
					(fill
						(type none)
					)
				)
				(pin passive line
					(at 0 0 0)
					(length 2.54)
					(name "1"
						(effects
							(font
								(size 1.27 1.27)
							)
						)
					)
					(number "1"
						(effects
							(font
								(size 1.27 1.27)
							)
						)
					)
				)
				(pin passive line
					(at 0 -5.08 0)
					(length 2.54)
					(name "4"
						(effects
							(font
								(size 1.27 1.27)
							)
						)
					)
					(number "4"
						(effects
							(font
								(size 1.27 1.27)
							)
						)
					)
				)
				(pin passive line
					(at 10.16 0 180)
					(length 2.54)
					(name "2"
						(effects
							(font
								(size 1.27 1.27)
							)
						)
					)
					(number "2"
						(effects
							(font
								(size 1.27 1.27)
							)
						)
					)
				)
				(pin passive line
					(at 10.16 -5.08 180)
					(length 2.54)
					(name "3"
						(effects
							(font
								(size 1.27 1.27)
							)
						)
					)
					(number "3"
						(effects
							(font
								(size 1.27 1.27)
							)
						)
					)
				)
			)
		)
	(symbol "antmicroDCDCConverters:AP62301_TSOT"
			(exclude_from_sim no)
			(in_bom yes)
			(on_board yes)
			(property "Reference" "U"
				(at 35.56 -2.54 0)
				(effects
					(font
						(size 1.27 1.27)
						(thickness 0.15)
					)
					(justify left bottom)
				)
			)
			(property "Value" "AP62301_TSOT"
				(at 35.56 -7.62 0)
				(effects
					(font
						(size 1.27 1.27)
						(thickness 0.15)
					)
					(justify left bottom)
					(hide yes)
				)
			)
			(property "Footprint" "antmicro-footprints:TSOT23-6"
				(at 35.56 -10.16 0)
				(effects
					(font
						(size 1.27 1.27)
						(thickness 0.15)
					)
					(justify left bottom)
					(hide yes)
				)
			)
			(property "Datasheet" "https://www.diodes.com/assets/Datasheets/AP62300_AP62301_AP62300T.pdf"
				(at 35.56 -12.7 0)
				(effects
					(font
						(size 1.27 1.27)
						(thickness 0.15)
					)
					(justify left bottom)
					(hide yes)
				)
			)
			(property "Description" "DC-DC Switching Synchronous Buck Regulator, Adjustable, 4.2V-18Vin, 0.8V-7V/3A out, TSOT-26-6"
				(at 0 0 0)
				(effects
					(font
						(size 1.27 1.27)
					)
					(hide yes)
				)
			)
			(property "MPN" "AP62301WU-7"
				(at 35.56 -5.08 0)
				(effects
					(font
						(size 1.27 1.27)
						(thickness 0.15)
					)
					(justify left bottom)
				)
			)
			(property "Manufacturer" "Diodes Incorporated"
				(at 35.56 -15.24 0)
				(effects
					(font
						(size 1.27 1.27)
						(thickness 0.15)
					)
					(justify left bottom)
					(hide yes)
				)
			)
			(property "Author" "Antmicro"
				(at 35.56 -17.78 0)
				(effects
					(font
						(size 1.27 1.27)
						(thickness 0.15)
					)
					(justify left bottom)
					(hide yes)
				)
			)
			(property "License" "Apache-2.0"
				(at 35.56 -20.32 0)
				(effects
					(font
						(size 1.27 1.27)
						(thickness 0.15)
					)
					(justify left bottom)
					(hide yes)
				)
			)
			(property "ki_keywords" "SMT, PMIC, IC, VOLTAGE"
				(at 0 0 0)
				(effects
					(font
						(size 1.27 1.27)
					)
					(hide yes)
				)
			)
			(symbol "AP62301_TSOT_1_1"
				(rectangle
					(start 2.54 2.54)
					(end 17.78 -12.7)
					(stroke
						(width 0.254)
						(type default)
					)
					(fill
						(type background)
					)
				)
				(pin power_in line
					(at 0 0 0)
					(length 2.54)
					(name "VIN"
						(effects
							(font
								(size 1.27 1.27)
							)
						)
					)
					(number "3"
						(effects
							(font
								(size 1.27 1.27)
							)
						)
					)
				)
				(pin input line
					(at 0 -5.08 0)
					(length 2.54)
					(name "EN"
						(effects
							(font
								(size 1.27 1.27)
							)
						)
					)
					(number "5"
						(effects
							(font
								(size 1.27 1.27)
							)
						)
					)
				)
				(pin power_in line
					(at 0 -10.16 0)
					(length 2.54)
					(name "GND"
						(effects
							(font
								(size 1.27 1.27)
							)
						)
					)
					(number "1"
						(effects
							(font
								(size 1.27 1.27)
							)
						)
					)
				)
				(pin power_out line
					(at 20.32 0 180)
					(length 2.54)
					(name "SW"
						(effects
							(font
								(size 1.27 1.27)
							)
						)
					)
					(number "2"
						(effects
							(font
								(size 1.27 1.27)
							)
						)
					)
				)
				(pin output line
					(at 20.32 -5.08 180)
					(length 2.54)
					(name "BST"
						(effects
							(font
								(size 1.27 1.27)
							)
						)
					)
					(number "6"
						(effects
							(font
								(size 1.27 1.27)
							)
						)
					)
				)
				(pin input line
					(at 20.32 -10.16 180)
					(length 2.54)
					(name "FB"
						(effects
							(font
								(size 1.27 1.27)
							)
						)
					)
					(number "4"
						(effects
							(font
								(size 1.27 1.27)
							)
						)
					)
				)
			)
		)
	(symbol "antmicroDCDCConverters:AP62600SJ-7"
			(exclude_from_sim no)
			(in_bom yes)
			(on_board yes)
			(property "Reference" "U"
				(at 35.56 -2.54 0)
				(effects
					(font
						(size 1.27 1.27)
						(thickness 0.15)
					)
					(justify left bottom)
				)
			)
			(property "Value" "AP62600SJ-7"
				(at 35.56 -7.62 0)
				(effects
					(font
						(size 1.27 1.27)
						(thickness 0.15)
					)
					(justify left bottom)
					(hide yes)
				)
			)
			(property "Footprint" "antmicro-footprints:V-QFN2030-12"
				(at 35.56 -10.16 0)
				(effects
					(font
						(size 1.27 1.27)
						(thickness 0.15)
					)
					(justify left bottom)
					(hide yes)
				)
			)
			(property "Datasheet" "https://www.diodes.com/assets/Datasheets/AP62600.pdf"
				(at 35.56 -12.7 0)
				(effects
					(font
						(size 1.27 1.27)
						(thickness 0.15)
					)
					(justify left bottom)
					(hide yes)
				)
			)
			(property "Description" "DC-DC Switching Synchronous Buck Regulator, Adjustable, 4.5V-18V in, 0.6 to 7 V/6 A out, VQFN2030-12"
				(at 0 0 0)
				(effects
					(font
						(size 1.27 1.27)
					)
					(hide yes)
				)
			)
			(property "MPN" "AP62600SJ-7"
				(at 35.56 -5.08 0)
				(effects
					(font
						(size 1.27 1.27)
						(thickness 0.15)
					)
					(justify left bottom)
				)
			)
			(property "Manufacturer" "Diodes Incorporated"
				(at 35.56 -15.24 0)
				(effects
					(font
						(size 1.27 1.27)
						(thickness 0.15)
					)
					(justify left bottom)
					(hide yes)
				)
			)
			(property "Author" "Antmicro"
				(at 35.56 -17.78 0)
				(effects
					(font
						(size 1.27 1.27)
						(thickness 0.15)
					)
					(justify left bottom)
					(hide yes)
				)
			)
			(property "License" "Apache-2.0"
				(at 35.56 -20.32 0)
				(effects
					(font
						(size 1.27 1.27)
						(thickness 0.15)
					)
					(justify left bottom)
					(hide yes)
				)
			)
			(property "ki_keywords" "SMT, PMIC, IC, VOLTAGE"
				(at 0 0 0)
				(effects
					(font
						(size 1.27 1.27)
					)
					(hide yes)
				)
			)
			(symbol "AP62600SJ-7_1_1"
				(rectangle
					(start 2.54 2.54)
					(end 20.32 -27.94)
					(stroke
						(width 0.254)
						(type default)
					)
					(fill
						(type background)
					)
				)
				(pin power_in line
					(at 0 0 0)
					(length 2.54)
					(name "VIN"
						(effects
							(font
								(size 1.27 1.27)
							)
						)
					)
					(number "2"
						(effects
							(font
								(size 1.27 1.27)
							)
						)
					)
				)
				(pin input line
					(at 0 -12.7 0)
					(length 2.54)
					(name "EN"
						(effects
							(font
								(size 1.27 1.27)
							)
						)
					)
					(number "3"
						(effects
							(font
								(size 1.27 1.27)
							)
						)
					)
				)
				(pin open_collector line
					(at 0 -15.24 0)
					(length 2.54)
					(name "PG"
						(effects
							(font
								(size 1.27 1.27)
							)
						)
					)
					(number "6"
						(effects
							(font
								(size 1.27 1.27)
							)
						)
					)
				)
				(pin input line
					(at 0 -17.78 0)
					(length 2.54)
					(name "FSEL"
						(effects
							(font
								(size 1.27 1.27)
							)
						)
					)
					(number "5"
						(effects
							(font
								(size 1.27 1.27)
							)
						)
					)
				)
				(pin input line
					(at 0 -20.32 0)
					(length 2.54)
					(name "MODE"
						(effects
							(font
								(size 1.27 1.27)
							)
						)
					)
					(number "4"
						(effects
							(font
								(size 1.27 1.27)
							)
						)
					)
				)
				(pin input line
					(at 0 -22.86 0)
					(length 2.54)
					(name "SS/TR"
						(effects
							(font
								(size 1.27 1.27)
							)
						)
					)
					(number "10"
						(effects
							(font
								(size 1.27 1.27)
							)
						)
					)
				)
				(pin passive line
					(at 0 -25.4 0)
					(length 2.54)
					(name "GND"
						(effects
							(font
								(size 1.27 1.27)
							)
						)
					)
					(number "11"
						(effects
							(font
								(size 1.27 1.27)
							)
						)
					)
				)
				(pin output line
					(at 22.86 0 180)
					(length 2.54)
					(name "SW"
						(effects
							(font
								(size 1.27 1.27)
							)
						)
					)
					(number "8"
						(effects
							(font
								(size 1.27 1.27)
							)
						)
					)
				)
				(pin input line
					(at 22.86 -7.62 180)
					(length 2.54)
					(name "BST"
						(effects
							(font
								(size 1.27 1.27)
							)
						)
					)
					(number "7"
						(effects
							(font
								(size 1.27 1.27)
							)
						)
					)
				)
				(pin input line
					(at 22.86 -12.7 180)
					(length 2.54)
					(name "FB"
						(effects
							(font
								(size 1.27 1.27)
							)
						)
					)
					(number "12"
						(effects
							(font
								(size 1.27 1.27)
							)
						)
					)
				)
				(pin input line
					(at 22.86 -17.78 180)
					(length 2.54)
					(name "VCC"
						(effects
							(font
								(size 1.27 1.27)
							)
						)
					)
					(number "9"
						(effects
							(font
								(size 1.27 1.27)
							)
						)
					)
				)
				(pin passive line
					(at 22.86 -25.4 180)
					(length 2.54)
					(name "PGND"
						(effects
							(font
								(size 1.27 1.27)
							)
						)
					)
					(number "1"
						(effects
							(font
								(size 1.27 1.27)
							)
						)
					)
				)
			)
		)
	(symbol "antmicroDCDCConverters:ULS-12_5-D48N-C"
			(exclude_from_sim no)
			(in_bom yes)
			(on_board yes)
			(property "Reference" "U"
				(at 33.02 -2.54 0)
				(effects
					(font
						(size 1.27 1.27)
						(thickness 0.15)
					)
					(justify left bottom)
				)
			)
			(property "Value" "ULS-12_5-D48N-C"
				(at 33.02 -7.62 0)
				(effects
					(font
						(size 1.27 1.27)
						(thickness 0.15)
					)
					(justify left bottom)
					(hide yes)
				)
			)
			(property "Footprint" "antmicro-footprints:Conv_Murata_ULS-60W"
				(at 33.02 -10.16 0)
				(effects
					(font
						(size 1.27 1.27)
						(thickness 0.15)
					)
					(justify left bottom)
					(hide yes)
				)
			)
			(property "Datasheet" "https://www.murata.com/products/productdata/8807040286750/uls.pdf?1649388617000"
				(at 33.02 -12.7 0)
				(effects
					(font
						(size 1.27 1.27)
						(thickness 0.15)
					)
					(justify left bottom)
					(hide yes)
				)
			)
			(property "Description" "Isolated Through Hole DC/DC Converter, ITE, 2:1, 60 W, 1 Output, 12 V, 5 A"
				(at 0 0 0)
				(effects
					(font
						(size 1.27 1.27)
					)
					(hide yes)
				)
			)
			(property "MPN" "ULS-12/5-D48N-C"
				(at 33.02 -5.08 0)
				(effects
					(font
						(size 1.27 1.27)
						(thickness 0.15)
					)
					(justify left bottom)
				)
			)
			(property "Manufacturer" "Murata"
				(at 33.02 -15.24 0)
				(effects
					(font
						(size 1.27 1.27)
						(thickness 0.15)
					)
					(justify left bottom)
					(hide yes)
				)
			)
			(property "Author" "Antmicro"
				(at 33.02 -17.78 0)
				(effects
					(font
						(size 1.27 1.27)
						(thickness 0.15)
					)
					(justify left bottom)
					(hide yes)
				)
			)
			(property "License" "Apache-2.0"
				(at 33.02 -20.32 0)
				(effects
					(font
						(size 1.27 1.27)
						(thickness 0.15)
					)
					(justify left bottom)
					(hide yes)
				)
			)
			(property "Alternatives 50W" " VCB4812SBO-50WR3, V36SE12004NRFA, PKU5513ESI, KHHD004A2B41Z"
				(at -10.16 -22.86 0)
				(show_name)
				(effects
					(font
						(size 1.27 1.27)
					)
					(justify left)
					(hide yes)
				)
			)
			(property "Alternatives 75W" " VCB4812SBO-75WR3"
				(at -10.16 -25.4 0)
				(show_name)
				(effects
					(font
						(size 1.27 1.27)
					)
					(justify left)
					(hide yes)
				)
			)
			(property "Alternatives 100W" "PKU4913DPIHS, VCB4812SBO-100WFR3"
				(at -10.16 -27.94 0)
				(show_name)
				(effects
					(font
						(size 1.27 1.27)
					)
					(justify left)
					(hide yes)
				)
			)
			(property "Alternatives 120W" "PQC50-48-S12-O"
				(at -10.16 -30.48 0)
				(show_name)
				(effects
					(font
						(size 1.27 1.27)
					)
					(justify left)
					(hide yes)
				)
			)
			(property "ki_keywords" "THT, PMIC, IC, DC-DC, CONVERTER, MODULE"
				(at 0 0 0)
				(effects
					(font
						(size 1.27 1.27)
					)
					(hide yes)
				)
			)
			(symbol "ULS-12_5-D48N-C_1_1"
				(rectangle
					(start 2.413 2.54)
					(end 17.653 -17.78)
					(stroke
						(width 0.254)
						(type default)
					)
					(fill
						(type background)
					)
				)
				(pin power_in line
					(at 0 0 0)
					(length 2.54)
					(name "VIN+"
						(effects
							(font
								(size 1.27 1.27)
							)
						)
					)
					(number "1"
						(effects
							(font
								(size 1.27 1.27)
							)
						)
					)
				)
				(pin input line
					(at 0 -7.62 0)
					(length 2.54)
					(name "CTRL"
						(effects
							(font
								(size 1.27 1.27)
							)
						)
					)
					(number "2"
						(effects
							(font
								(size 1.27 1.27)
							)
						)
					)
				)
				(pin power_in line
					(at 0 -15.24 0)
					(length 2.54)
					(name "VIN-"
						(effects
							(font
								(size 1.27 1.27)
							)
						)
					)
					(number "3"
						(effects
							(font
								(size 1.27 1.27)
							)
						)
					)
				)
				(pin power_out line
					(at 20.32 0 180)
					(length 2.54)
					(name "VOUT+"
						(effects
							(font
								(size 1.27 1.27)
							)
						)
					)
					(number "8"
						(effects
							(font
								(size 1.27 1.27)
							)
						)
					)
				)
				(pin passive line
					(at 20.32 -2.54 180)
					(length 2.54)
					(name "SENSE+"
						(effects
							(font
								(size 1.27 1.27)
							)
						)
					)
					(number "7"
						(effects
							(font
								(size 1.27 1.27)
							)
						)
					)
				)
				(pin input line
					(at 20.32 -7.62 180)
					(length 2.54)
					(name "TRIM"
						(effects
							(font
								(size 1.27 1.27)
							)
						)
					)
					(number "6"
						(effects
							(font
								(size 1.27 1.27)
							)
						)
					)
				)
				(pin passive line
					(at 20.32 -12.7 180)
					(length 2.54)
					(name "SENSE-"
						(effects
							(font
								(size 1.27 1.27)
							)
						)
					)
					(number "5"
						(effects
							(font
								(size 1.27 1.27)
							)
						)
					)
				)
				(pin power_out line
					(at 20.32 -15.24 180)
					(length 2.54)
					(name "VOUT-"
						(effects
							(font
								(size 1.27 1.27)
							)
						)
					)
					(number "4"
						(effects
							(font
								(size 1.27 1.27)
							)
						)
					)
				)
			)
		)
	(symbol "antmicroDiodesRectifiersSingle:CD-MMBL110S"
			(pin_names
				(hide yes)
			)
			(exclude_from_sim no)
			(in_bom yes)
			(on_board yes)
			(property "Reference" "D"
				(at 26.67 -2.54 0)
				(effects
					(font
						(size 1.27 1.27)
						(thickness 0.15)
					)
					(justify left bottom)
				)
			)
			(property "Value" "CD-MMBL110S"
				(at 26.67 -12.7 0)
				(effects
					(font
						(size 1.27 1.27)
						(thickness 0.15)
					)
					(justify left bottom)
					(hide yes)
				)
			)
			(property "Footprint" "antmicro-footprints:DFN3538"
				(at 26.67 -7.62 0)
				(effects
					(font
						(size 1.27 1.27)
						(thickness 0.15)
					)
					(justify left bottom)
					(hide yes)
				)
			)
			(property "Datasheet" "https://www.bourns.com/docs/product-datasheets/CD-MMBL110S.pdf"
				(at 26.67 -10.16 0)
				(effects
					(font
						(size 1.27 1.27)
						(thickness 0.15)
					)
					(justify left bottom)
					(hide yes)
				)
			)
			(property "Description" "Bridge Rectifier, 1000 V, 1 A, Single Phase , 4 Pins, 900mV"
				(at 0 0 0)
				(effects
					(font
						(size 1.27 1.27)
					)
					(hide yes)
				)
			)
			(property "MPN" "CD-MMBL110S"
				(at 26.67 -5.08 0)
				(effects
					(font
						(size 1.27 1.27)
						(thickness 0.15)
					)
					(justify left bottom)
				)
			)
			(property "Manufacturer" "Bourns"
				(at 26.67 -15.24 0)
				(effects
					(font
						(size 1.27 1.27)
						(thickness 0.15)
					)
					(justify left bottom)
					(hide yes)
				)
			)
			(property "Author" "Antmicro"
				(at 26.67 -17.78 0)
				(effects
					(font
						(size 1.27 1.27)
						(thickness 0.15)
					)
					(justify left bottom)
					(hide yes)
				)
			)
			(property "License" "Apache-2.0"
				(at 26.67 -20.32 0)
				(effects
					(font
						(size 1.27 1.27)
						(thickness 0.15)
					)
					(justify left bottom)
					(hide yes)
				)
			)
			(property "ki_keywords" "SMT, RECTIFIER, SEMICONDUCTOR, DIODE, BRIDGE"
				(at 0 0 0)
				(effects
					(font
						(size 1.27 1.27)
					)
					(hide yes)
				)
			)
			(symbol "CD-MMBL110S_1_1"
				(rectangle
					(start 2.54 1.27)
					(end 15.24 -11.43)
					(stroke
						(width 0.254)
						(type default)
					)
					(fill
						(type background)
					)
				)
				(polyline
					(pts
						(xy 2.54 -5.08) (xy 3.81 -5.08)
					)
					(stroke
						(width 0.254)
						(type default)
					)
					(fill
						(type none)
					)
				)
				(polyline
					(pts
						(xy 3.81 0) (xy 2.54 0)
					)
					(stroke
						(width 0.254)
						(type default)
					)
					(fill
						(type none)
					)
				)
				(polyline
					(pts
						(xy 3.81 -2.54) (xy 3.81 -3.81)
					)
					(stroke
						(width 0.254)
						(type default)
					)
					(fill
						(type none)
					)
				)
				(polyline
					(pts
						(xy 3.81 -3.81) (xy 3.81 -7.62)
					)
					(stroke
						(width 0.254)
						(type default)
					)
					(fill
						(type none)
					)
				)
				(polyline
					(pts
						(xy 3.81 -10.16) (xy 2.54 -10.16)
					)
					(stroke
						(width 0.254)
						(type default)
					)
					(fill
						(type none)
					)
				)
				(polyline
					(pts
						(xy 5.08 -1.27) (xy 5.08 -3.81) (xy 7.62 -2.54) (xy 5.08 -1.27)
					)
					(stroke
						(width 0.254)
						(type default)
					)
					(fill
						(type outline)
					)
				)
				(polyline
					(pts
						(xy 5.08 -2.54) (xy 3.81 -2.54)
					)
					(stroke
						(width 0.254)
						(type default)
					)
					(fill
						(type none)
					)
				)
				(polyline
					(pts
						(xy 5.08 -6.35) (xy 5.08 -8.89) (xy 7.62 -7.62) (xy 5.08 -6.35)
					)
					(stroke
						(width 0.254)
						(type default)
					)
					(fill
						(type outline)
					)
				)
				(polyline
					(pts
						(xy 5.08 -7.62) (xy 3.81 -7.62)
					)
					(stroke
						(width 0.254)
						(type default)
					)
					(fill
						(type none)
					)
				)
				(polyline
					(pts
						(xy 7.62 -1.27) (xy 7.62 -3.81)
					)
					(stroke
						(width 0.254)
						(type default)
					)
					(fill
						(type none)
					)
				)
				(polyline
					(pts
						(xy 7.62 -6.35) (xy 7.62 -8.89)
					)
					(stroke
						(width 0.254)
						(type default)
					)
					(fill
						(type none)
					)
				)
				(polyline
					(pts
						(xy 8.89 -2.54) (xy 7.62 -2.54)
					)
					(stroke
						(width 0.254)
						(type default)
					)
					(fill
						(type none)
					)
				)
				(polyline
					(pts
						(xy 8.89 -2.54) (xy 8.89 0) (xy 3.81 0)
					)
					(stroke
						(width 0.254)
						(type default)
					)
					(fill
						(type none)
					)
				)
				(polyline
					(pts
						(xy 8.89 -7.62) (xy 7.62 -7.62)
					)
					(stroke
						(width 0.254)
						(type default)
					)
					(fill
						(type none)
					)
				)
				(polyline
					(pts
						(xy 8.89 -7.62) (xy 8.89 -10.16) (xy 3.81 -10.16)
					)
					(stroke
						(width 0.254)
						(type default)
					)
					(fill
						(type none)
					)
				)
				(polyline
					(pts
						(xy 10.16 -1.27) (xy 10.16 -3.81) (xy 12.7 -2.54) (xy 10.16 -1.27)
					)
					(stroke
						(width 0.254)
						(type default)
					)
					(fill
						(type outline)
					)
				)
				(polyline
					(pts
						(xy 10.16 -2.54) (xy 6.35 -2.54)
					)
					(stroke
						(width 0.254)
						(type default)
					)
					(fill
						(type none)
					)
				)
				(polyline
					(pts
						(xy 10.16 -6.35) (xy 10.16 -8.89) (xy 12.7 -7.62) (xy 10.16 -6.35)
					)
					(stroke
						(width 0.254)
						(type default)
					)
					(fill
						(type outline)
					)
				)
				(polyline
					(pts
						(xy 10.16 -7.62) (xy 6.35 -7.62)
					)
					(stroke
						(width 0.254)
						(type default)
					)
					(fill
						(type none)
					)
				)
				(polyline
					(pts
						(xy 12.7 -1.27) (xy 12.7 -3.81)
					)
					(stroke
						(width 0.254)
						(type default)
					)
					(fill
						(type none)
					)
				)
				(polyline
					(pts
						(xy 12.7 -2.54) (xy 13.97 -2.54)
					)
					(stroke
						(width 0.254)
						(type default)
					)
					(fill
						(type none)
					)
				)
				(polyline
					(pts
						(xy 12.7 -6.35) (xy 12.7 -8.89)
					)
					(stroke
						(width 0.254)
						(type default)
					)
					(fill
						(type none)
					)
				)
				(polyline
					(pts
						(xy 12.7 -7.62) (xy 13.97 -7.62)
					)
					(stroke
						(width 0.254)
						(type default)
					)
					(fill
						(type none)
					)
				)
				(polyline
					(pts
						(xy 13.97 -2.54) (xy 13.97 -3.81)
					)
					(stroke
						(width 0.254)
						(type default)
					)
					(fill
						(type none)
					)
				)
				(polyline
					(pts
						(xy 13.97 -3.81) (xy 13.97 -7.62)
					)
					(stroke
						(width 0.254)
						(type default)
					)
					(fill
						(type none)
					)
				)
				(polyline
					(pts
						(xy 13.97 -5.08) (xy 15.24 -5.08)
					)
					(stroke
						(width 0.254)
						(type default)
					)
					(fill
						(type none)
					)
				)
				(pin passive line
					(at 0 0 0)
					(length 2.54)
					(name "3"
						(effects
							(font
								(size 1.27 1.27)
							)
						)
					)
					(number "3"
						(effects
							(font
								(size 1.27 1.27)
							)
						)
					)
				)
				(pin passive line
					(at 0 -5.08 0)
					(length 2.54)
					(name "1"
						(effects
							(font
								(size 1.27 1.27)
							)
						)
					)
					(number "1"
						(effects
							(font
								(size 1.27 1.27)
							)
						)
					)
				)
				(pin passive line
					(at 0 -10.16 0)
					(length 2.54)
					(name "4"
						(effects
							(font
								(size 1.27 1.27)
							)
						)
					)
					(number "4"
						(effects
							(font
								(size 1.27 1.27)
							)
						)
					)
				)
				(pin passive line
					(at 17.78 -5.08 180)
					(length 2.54)
					(name "2"
						(effects
							(font
								(size 1.27 1.27)
							)
						)
					)
					(number "2"
						(effects
							(font
								(size 1.27 1.27)
							)
						)
					)
				)
			)
		)
	(symbol "antmicroDiodesRectifiersSingle:RB521S30T1G"
			(pin_numbers
				(hide yes)
			)
			(pin_names
				(hide yes)
			)
			(exclude_from_sim no)
			(in_bom yes)
			(on_board yes)
			(property "Reference" "D"
				(at 22.86 -5.08 0)
				(effects
					(font
						(size 1.27 1.27)
						(thickness 0.15)
					)
					(justify left bottom)
				)
			)
			(property "Value" "RB521S30T1G"
				(at 22.86 -15.24 0)
				(effects
					(font
						(size 1.27 1.27)
						(thickness 0.15)
					)
					(justify left bottom)
					(hide yes)
				)
			)
			(property "Footprint" "antmicro-footprints:SOD-523"
				(at 22.86 -10.16 0)
				(effects
					(font
						(size 1.27 1.27)
						(thickness 0.15)
					)
					(justify left bottom)
					(hide yes)
				)
			)
			(property "Datasheet" "https://www.onsemi.com/pdf/datasheet/rb521s30t1-d.pdf"
				(at 22.86 -12.7 0)
				(effects
					(font
						(size 1.27 1.27)
						(thickness 0.15)
					)
					(justify left bottom)
					(hide yes)
				)
			)
			(property "Description" "Small Signal Schottky Diode, Single, 30 V, 200 mA, 500 mV, 1 A, 125 °C"
				(at 0 0 0)
				(effects
					(font
						(size 1.27 1.27)
					)
					(hide yes)
				)
			)
			(property "MPN" "RB521S30T1G"
				(at 22.86 -7.62 0)
				(effects
					(font
						(size 1.27 1.27)
						(thickness 0.15)
					)
					(justify left bottom)
				)
			)
			(property "Manufacturer" "ON Semiconductor"
				(at 22.86 -17.78 0)
				(effects
					(font
						(size 1.27 1.27)
						(thickness 0.15)
					)
					(justify left bottom)
					(hide yes)
				)
			)
			(property "Author" "Antmicro"
				(at 22.86 -20.32 0)
				(effects
					(font
						(size 1.27 1.27)
						(thickness 0.15)
					)
					(justify left bottom)
					(hide yes)
				)
			)
			(property "License" "Apache-2.0"
				(at 22.86 -22.86 0)
				(effects
					(font
						(size 1.27 1.27)
						(thickness 0.15)
					)
					(justify left bottom)
					(hide yes)
				)
			)
			(property "ki_keywords" "SMT, SEMICONDUCTOR, DIODE, SCHOTTKY"
				(at 0 0 0)
				(effects
					(font
						(size 1.27 1.27)
					)
					(hide yes)
				)
			)
			(symbol "RB521S30T1G_0_1"
				(polyline
					(pts
						(xy 1.905 0) (xy 0.635 0)
					)
					(stroke
						(width 0)
						(type default)
					)
					(fill
						(type none)
					)
				)
				(polyline
					(pts
						(xy 4.445 0) (xy 3.175 0)
					)
					(stroke
						(width 0)
						(type default)
					)
					(fill
						(type none)
					)
				)
			)
			(symbol "RB521S30T1G_1_1"
				(polyline
					(pts
						(xy 1.778 1.016) (xy 1.778 -1.016)
					)
					(stroke
						(width 0.254)
						(type default)
					)
					(fill
						(type none)
					)
				)
				(polyline
					(pts
						(xy 1.778 1.016) (xy 1.397 1.016) (xy 1.397 0.762)
					)
					(stroke
						(width 0.254)
						(type default)
					)
					(fill
						(type none)
					)
				)
				(polyline
					(pts
						(xy 1.778 -1.016) (xy 2.159 -1.016) (xy 2.159 -0.762)
					)
					(stroke
						(width 0.254)
						(type default)
					)
					(fill
						(type none)
					)
				)
				(polyline
					(pts
						(xy 3.302 1.016) (xy 3.302 -1.016) (xy 1.778 0) (xy 3.302 1.016)
					)
					(stroke
						(width 0.254)
						(type default)
					)
					(fill
						(type outline)
					)
				)
				(pin passive line
					(at 0 0 0)
					(length 0.635)
					(name "C"
						(effects
							(font
								(size 1.27 1.27)
							)
						)
					)
					(number "1"
						(effects
							(font
								(size 1.27 1.27)
							)
						)
					)
				)
				(pin passive line
					(at 5.08 0 180)
					(length 0.635)
					(name "A"
						(effects
							(font
								(size 1.27 1.27)
							)
						)
					)
					(number "2"
						(effects
							(font
								(size 1.27 1.27)
							)
						)
					)
				)
			)
		)
	(symbol "antmicroFCCConnectors:Conn_FFC_WE_68715014522"
			(exclude_from_sim no)
			(in_bom yes)
			(on_board yes)
			(property "Reference" "J"
				(at 19.05 -5.08 0)
				(effects
					(font
						(size 1.27 1.27)
						(thickness 0.15)
					)
					(justify left bottom)
				)
			)
			(property "Value" "Conn_FFC_WE_68715014522"
				(at 19.05 -7.62 0)
				(effects
					(font
						(size 1.27 1.27)
						(thickness 0.15)
					)
					(justify left bottom)
					(hide yes)
				)
			)
			(property "Footprint" "antmicro-footprints:Conn_FFC_WE_68715014x22"
				(at 19.05 -10.16 0)
				(effects
					(font
						(size 1.27 1.27)
						(thickness 0.15)
					)
					(justify left bottom)
					(hide yes)
				)
			)
			(property "Datasheet" "https://www.we-online.com/components/products/datasheet/68715014522.pdf"
				(at 19.05 -12.7 0)
				(effects
					(font
						(size 1.27 1.27)
						(thickness 0.15)
					)
					(justify left bottom)
					(hide yes)
				)
			)
			(property "Description" "FFC connector"
				(at 0 0 0)
				(effects
					(font
						(size 1.27 1.27)
					)
					(hide yes)
				)
			)
			(property "MPN" "68715014522"
				(at 19.05 -15.24 0)
				(effects
					(font
						(size 1.27 1.27)
						(thickness 0.15)
					)
					(justify left bottom)
				)
			)
			(property "Manufacturer" "Würth Elektronik"
				(at 19.05 -17.78 0)
				(effects
					(font
						(size 1.27 1.27)
						(thickness 0.15)
					)
					(justify left bottom)
					(hide yes)
				)
			)
			(property "Author" "Antmicro"
				(at 19.05 -20.32 0)
				(effects
					(font
						(size 1.27 1.27)
						(thickness 0.15)
					)
					(justify left bottom)
					(hide yes)
				)
			)
			(property "License" "Apache-2.0"
				(at 19.05 -22.86 0)
				(effects
					(font
						(size 1.27 1.27)
						(thickness 0.15)
					)
					(justify left bottom)
					(hide yes)
				)
			)
			(property "ki_keywords" "CONNECTOR"
				(at 0 0 0)
				(effects
					(font
						(size 1.27 1.27)
					)
					(hide yes)
				)
			)
			(symbol "Conn_FFC_WE_68715014522_1_1"
				(rectangle
					(start 3.81 1.27)
					(end 7.62 -132.08)
					(stroke
						(width 0.254)
						(type default)
					)
					(fill
						(type background)
					)
				)
				(rectangle
					(start 3.81 0.127)
					(end 5.08 -0.127)
					(stroke
						(width 0.254)
						(type default)
					)
					(fill
						(type background)
					)
				)
				(rectangle
					(start 3.81 -2.413)
					(end 5.08 -2.667)
					(stroke
						(width 0.254)
						(type default)
					)
					(fill
						(type background)
					)
				)
				(rectangle
					(start 3.81 -4.953)
					(end 5.08 -5.207)
					(stroke
						(width 0.254)
						(type default)
					)
					(fill
						(type background)
					)
				)
				(rectangle
					(start 3.81 -7.493)
					(end 5.08 -7.747)
					(stroke
						(width 0.254)
						(type default)
					)
					(fill
						(type background)
					)
				)
				(rectangle
					(start 3.81 -10.033)
					(end 5.08 -10.287)
					(stroke
						(width 0.254)
						(type default)
					)
					(fill
						(type background)
					)
				)
				(rectangle
					(start 3.81 -12.573)
					(end 5.08 -12.827)
					(stroke
						(width 0.254)
						(type default)
					)
					(fill
						(type background)
					)
				)
				(rectangle
					(start 3.81 -15.113)
					(end 5.08 -15.367)
					(stroke
						(width 0.254)
						(type default)
					)
					(fill
						(type background)
					)
				)
				(rectangle
					(start 3.81 -17.653)
					(end 5.08 -17.907)
					(stroke
						(width 0.254)
						(type default)
					)
					(fill
						(type background)
					)
				)
				(rectangle
					(start 3.81 -20.193)
					(end 5.08 -20.447)
					(stroke
						(width 0.254)
						(type default)
					)
					(fill
						(type background)
					)
				)
				(rectangle
					(start 3.81 -22.733)
					(end 5.08 -22.987)
					(stroke
						(width 0.254)
						(type default)
					)
					(fill
						(type background)
					)
				)
				(rectangle
					(start 3.81 -25.273)
					(end 5.08 -25.527)
					(stroke
						(width 0.254)
						(type default)
					)
					(fill
						(type background)
					)
				)
				(rectangle
					(start 3.81 -27.813)
					(end 5.08 -28.067)
					(stroke
						(width 0.254)
						(type default)
					)
					(fill
						(type background)
					)
				)
				(rectangle
					(start 3.81 -30.353)
					(end 5.08 -30.607)
					(stroke
						(width 0.254)
						(type default)
					)
					(fill
						(type background)
					)
				)
				(rectangle
					(start 3.81 -32.893)
					(end 5.08 -33.147)
					(stroke
						(width 0.254)
						(type default)
					)
					(fill
						(type background)
					)
				)
				(rectangle
					(start 3.81 -35.433)
					(end 5.08 -35.687)
					(stroke
						(width 0.254)
						(type default)
					)
					(fill
						(type background)
					)
				)
				(rectangle
					(start 3.81 -37.973)
					(end 5.08 -38.227)
					(stroke
						(width 0.254)
						(type default)
					)
					(fill
						(type background)
					)
				)
				(rectangle
					(start 3.81 -40.513)
					(end 5.08 -40.767)
					(stroke
						(width 0.254)
						(type default)
					)
					(fill
						(type background)
					)
				)
				(rectangle
					(start 3.81 -43.053)
					(end 5.08 -43.307)
					(stroke
						(width 0.254)
						(type default)
					)
					(fill
						(type background)
					)
				)
				(rectangle
					(start 3.81 -45.593)
					(end 5.08 -45.847)
					(stroke
						(width 0.254)
						(type default)
					)
					(fill
						(type background)
					)
				)
				(rectangle
					(start 3.81 -48.133)
					(end 5.08 -48.387)
					(stroke
						(width 0.254)
						(type default)
					)
					(fill
						(type background)
					)
				)
				(rectangle
					(start 3.81 -50.673)
					(end 5.08 -50.927)
					(stroke
						(width 0.254)
						(type default)
					)
					(fill
						(type background)
					)
				)
				(rectangle
					(start 3.81 -53.213)
					(end 5.08 -53.467)
					(stroke
						(width 0.254)
						(type default)
					)
					(fill
						(type background)
					)
				)
				(rectangle
					(start 3.81 -55.753)
					(end 5.08 -56.007)
					(stroke
						(width 0.254)
						(type default)
					)
					(fill
						(type background)
					)
				)
				(rectangle
					(start 3.81 -58.293)
					(end 5.08 -58.547)
					(stroke
						(width 0.254)
						(type default)
					)
					(fill
						(type background)
					)
				)
				(rectangle
					(start 3.81 -60.833)
					(end 5.08 -61.087)
					(stroke
						(width 0.254)
						(type default)
					)
					(fill
						(type background)
					)
				)
				(rectangle
					(start 3.81 -63.373)
					(end 5.08 -63.627)
					(stroke
						(width 0.254)
						(type default)
					)
					(fill
						(type background)
					)
				)
				(rectangle
					(start 3.81 -65.913)
					(end 5.08 -66.167)
					(stroke
						(width 0.254)
						(type default)
					)
					(fill
						(type background)
					)
				)
				(rectangle
					(start 3.81 -68.453)
					(end 5.08 -68.707)
					(stroke
						(width 0.254)
						(type default)
					)
					(fill
						(type background)
					)
				)
				(rectangle
					(start 3.81 -70.993)
					(end 5.08 -71.247)
					(stroke
						(width 0.254)
						(type default)
					)
					(fill
						(type background)
					)
				)
				(rectangle
					(start 3.81 -73.533)
					(end 5.08 -73.787)
					(stroke
						(width 0.254)
						(type default)
					)
					(fill
						(type background)
					)
				)
				(rectangle
					(start 3.81 -76.073)
					(end 5.08 -76.327)
					(stroke
						(width 0.254)
						(type default)
					)
					(fill
						(type background)
					)
				)
				(rectangle
					(start 3.81 -78.613)
					(end 5.08 -78.867)
					(stroke
						(width 0.254)
						(type default)
					)
					(fill
						(type background)
					)
				)
				(rectangle
					(start 3.81 -81.153)
					(end 5.08 -81.407)
					(stroke
						(width 0.254)
						(type default)
					)
					(fill
						(type background)
					)
				)
				(rectangle
					(start 3.81 -83.693)
					(end 5.08 -83.947)
					(stroke
						(width 0.254)
						(type default)
					)
					(fill
						(type background)
					)
				)
				(rectangle
					(start 3.81 -86.233)
					(end 5.08 -86.487)
					(stroke
						(width 0.254)
						(type default)
					)
					(fill
						(type background)
					)
				)
				(rectangle
					(start 3.81 -88.773)
					(end 5.08 -89.027)
					(stroke
						(width 0.254)
						(type default)
					)
					(fill
						(type background)
					)
				)
				(rectangle
					(start 3.81 -91.313)
					(end 5.08 -91.567)
					(stroke
						(width 0.254)
						(type default)
					)
					(fill
						(type background)
					)
				)
				(rectangle
					(start 3.81 -93.853)
					(end 5.08 -94.107)
					(stroke
						(width 0.254)
						(type default)
					)
					(fill
						(type background)
					)
				)
				(rectangle
					(start 3.81 -96.393)
					(end 5.08 -96.647)
					(stroke
						(width 0.254)
						(type default)
					)
					(fill
						(type background)
					)
				)
				(rectangle
					(start 3.81 -98.933)
					(end 5.08 -99.187)
					(stroke
						(width 0.254)
						(type default)
					)
					(fill
						(type background)
					)
				)
				(rectangle
					(start 3.81 -101.473)
					(end 5.08 -101.727)
					(stroke
						(width 0.254)
						(type default)
					)
					(fill
						(type background)
					)
				)
				(rectangle
					(start 3.81 -104.013)
					(end 5.08 -104.267)
					(stroke
						(width 0.254)
						(type default)
					)
					(fill
						(type background)
					)
				)
				(rectangle
					(start 3.81 -106.553)
					(end 5.08 -106.807)
					(stroke
						(width 0.254)
						(type default)
					)
					(fill
						(type background)
					)
				)
				(rectangle
					(start 3.81 -109.093)
					(end 5.08 -109.347)
					(stroke
						(width 0.254)
						(type default)
					)
					(fill
						(type background)
					)
				)
				(rectangle
					(start 3.81 -111.633)
					(end 5.08 -111.887)
					(stroke
						(width 0.254)
						(type default)
					)
					(fill
						(type background)
					)
				)
				(rectangle
					(start 3.81 -114.173)
					(end 5.08 -114.427)
					(stroke
						(width 0.254)
						(type default)
					)
					(fill
						(type background)
					)
				)
				(rectangle
					(start 3.81 -116.713)
					(end 5.08 -116.967)
					(stroke
						(width 0.254)
						(type default)
					)
					(fill
						(type background)
					)
				)
				(rectangle
					(start 3.81 -119.253)
					(end 5.08 -119.507)
					(stroke
						(width 0.254)
						(type default)
					)
					(fill
						(type background)
					)
				)
				(rectangle
					(start 3.81 -121.793)
					(end 5.08 -122.047)
					(stroke
						(width 0.254)
						(type default)
					)
					(fill
						(type background)
					)
				)
				(rectangle
					(start 3.81 -124.333)
					(end 5.08 -124.587)
					(stroke
						(width 0.254)
						(type default)
					)
					(fill
						(type background)
					)
				)
				(pin passive line
					(at 0 0 0)
					(length 3.81)
					(name "~"
						(effects
							(font
								(size 1.27 1.27)
							)
						)
					)
					(number "1"
						(effects
							(font
								(size 1.27 1.27)
							)
						)
					)
				)
				(pin passive line
					(at 0 -2.54 0)
					(length 3.81)
					(name "~"
						(effects
							(font
								(size 1.27 1.27)
							)
						)
					)
					(number "2"
						(effects
							(font
								(size 1.27 1.27)
							)
						)
					)
				)
				(pin passive line
					(at 0 -5.08 0)
					(length 3.81)
					(name "~"
						(effects
							(font
								(size 1.27 1.27)
							)
						)
					)
					(number "3"
						(effects
							(font
								(size 1.27 1.27)
							)
						)
					)
				)
				(pin passive line
					(at 0 -7.62 0)
					(length 3.81)
					(name "~"
						(effects
							(font
								(size 1.27 1.27)
							)
						)
					)
					(number "4"
						(effects
							(font
								(size 1.27 1.27)
							)
						)
					)
				)
				(pin passive line
					(at 0 -10.16 0)
					(length 3.81)
					(name "~"
						(effects
							(font
								(size 1.27 1.27)
							)
						)
					)
					(number "5"
						(effects
							(font
								(size 1.27 1.27)
							)
						)
					)
				)
				(pin passive line
					(at 0 -12.7 0)
					(length 3.81)
					(name "~"
						(effects
							(font
								(size 1.27 1.27)
							)
						)
					)
					(number "6"
						(effects
							(font
								(size 1.27 1.27)
							)
						)
					)
				)
				(pin passive line
					(at 0 -15.24 0)
					(length 3.81)
					(name "~"
						(effects
							(font
								(size 1.27 1.27)
							)
						)
					)
					(number "7"
						(effects
							(font
								(size 1.27 1.27)
							)
						)
					)
				)
				(pin passive line
					(at 0 -17.78 0)
					(length 3.81)
					(name "~"
						(effects
							(font
								(size 1.27 1.27)
							)
						)
					)
					(number "8"
						(effects
							(font
								(size 1.27 1.27)
							)
						)
					)
				)
				(pin passive line
					(at 0 -20.32 0)
					(length 3.81)
					(name "~"
						(effects
							(font
								(size 1.27 1.27)
							)
						)
					)
					(number "9"
						(effects
							(font
								(size 1.27 1.27)
							)
						)
					)
				)
				(pin passive line
					(at 0 -22.86 0)
					(length 3.81)
					(name "~"
						(effects
							(font
								(size 1.27 1.27)
							)
						)
					)
					(number "10"
						(effects
							(font
								(size 1.27 1.27)
							)
						)
					)
				)
				(pin passive line
					(at 0 -25.4 0)
					(length 3.81)
					(name "~"
						(effects
							(font
								(size 1.27 1.27)
							)
						)
					)
					(number "11"
						(effects
							(font
								(size 1.27 1.27)
							)
						)
					)
				)
				(pin passive line
					(at 0 -27.94 0)
					(length 3.81)
					(name "~"
						(effects
							(font
								(size 1.27 1.27)
							)
						)
					)
					(number "12"
						(effects
							(font
								(size 1.27 1.27)
							)
						)
					)
				)
				(pin passive line
					(at 0 -30.48 0)
					(length 3.81)
					(name "~"
						(effects
							(font
								(size 1.27 1.27)
							)
						)
					)
					(number "13"
						(effects
							(font
								(size 1.27 1.27)
							)
						)
					)
				)
				(pin passive line
					(at 0 -33.02 0)
					(length 3.81)
					(name "~"
						(effects
							(font
								(size 1.27 1.27)
							)
						)
					)
					(number "14"
						(effects
							(font
								(size 1.27 1.27)
							)
						)
					)
				)
				(pin passive line
					(at 0 -35.56 0)
					(length 3.81)
					(name "~"
						(effects
							(font
								(size 1.27 1.27)
							)
						)
					)
					(number "15"
						(effects
							(font
								(size 1.27 1.27)
							)
						)
					)
				)
				(pin passive line
					(at 0 -38.1 0)
					(length 3.81)
					(name "~"
						(effects
							(font
								(size 1.27 1.27)
							)
						)
					)
					(number "16"
						(effects
							(font
								(size 1.27 1.27)
							)
						)
					)
				)
				(pin passive line
					(at 0 -40.64 0)
					(length 3.81)
					(name "~"
						(effects
							(font
								(size 1.27 1.27)
							)
						)
					)
					(number "17"
						(effects
							(font
								(size 1.27 1.27)
							)
						)
					)
				)
				(pin passive line
					(at 0 -43.18 0)
					(length 3.81)
					(name "~"
						(effects
							(font
								(size 1.27 1.27)
							)
						)
					)
					(number "18"
						(effects
							(font
								(size 1.27 1.27)
							)
						)
					)
				)
				(pin passive line
					(at 0 -45.72 0)
					(length 3.81)
					(name "~"
						(effects
							(font
								(size 1.27 1.27)
							)
						)
					)
					(number "19"
						(effects
							(font
								(size 1.27 1.27)
							)
						)
					)
				)
				(pin passive line
					(at 0 -48.26 0)
					(length 3.81)
					(name "~"
						(effects
							(font
								(size 1.27 1.27)
							)
						)
					)
					(number "20"
						(effects
							(font
								(size 1.27 1.27)
							)
						)
					)
				)
				(pin passive line
					(at 0 -50.8 0)
					(length 3.81)
					(name "~"
						(effects
							(font
								(size 1.27 1.27)
							)
						)
					)
					(number "21"
						(effects
							(font
								(size 1.27 1.27)
							)
						)
					)
				)
				(pin passive line
					(at 0 -53.34 0)
					(length 3.81)
					(name "~"
						(effects
							(font
								(size 1.27 1.27)
							)
						)
					)
					(number "22"
						(effects
							(font
								(size 1.27 1.27)
							)
						)
					)
				)
				(pin passive line
					(at 0 -55.88 0)
					(length 3.81)
					(name "~"
						(effects
							(font
								(size 1.27 1.27)
							)
						)
					)
					(number "23"
						(effects
							(font
								(size 1.27 1.27)
							)
						)
					)
				)
				(pin passive line
					(at 0 -58.42 0)
					(length 3.81)
					(name "~"
						(effects
							(font
								(size 1.27 1.27)
							)
						)
					)
					(number "24"
						(effects
							(font
								(size 1.27 1.27)
							)
						)
					)
				)
				(pin passive line
					(at 0 -60.96 0)
					(length 3.81)
					(name "~"
						(effects
							(font
								(size 1.27 1.27)
							)
						)
					)
					(number "25"
						(effects
							(font
								(size 1.27 1.27)
							)
						)
					)
				)
				(pin passive line
					(at 0 -63.5 0)
					(length 3.81)
					(name "~"
						(effects
							(font
								(size 1.27 1.27)
							)
						)
					)
					(number "26"
						(effects
							(font
								(size 1.27 1.27)
							)
						)
					)
				)
				(pin passive line
					(at 0 -66.04 0)
					(length 3.81)
					(name "~"
						(effects
							(font
								(size 1.27 1.27)
							)
						)
					)
					(number "27"
						(effects
							(font
								(size 1.27 1.27)
							)
						)
					)
				)
				(pin passive line
					(at 0 -68.58 0)
					(length 3.81)
					(name "~"
						(effects
							(font
								(size 1.27 1.27)
							)
						)
					)
					(number "28"
						(effects
							(font
								(size 1.27 1.27)
							)
						)
					)
				)
				(pin passive line
					(at 0 -71.12 0)
					(length 3.81)
					(name "~"
						(effects
							(font
								(size 1.27 1.27)
							)
						)
					)
					(number "29"
						(effects
							(font
								(size 1.27 1.27)
							)
						)
					)
				)
				(pin passive line
					(at 0 -73.66 0)
					(length 3.81)
					(name "~"
						(effects
							(font
								(size 1.27 1.27)
							)
						)
					)
					(number "30"
						(effects
							(font
								(size 1.27 1.27)
							)
						)
					)
				)
				(pin passive line
					(at 0 -76.2 0)
					(length 3.81)
					(name "~"
						(effects
							(font
								(size 1.27 1.27)
							)
						)
					)
					(number "31"
						(effects
							(font
								(size 1.27 1.27)
							)
						)
					)
				)
				(pin passive line
					(at 0 -78.74 0)
					(length 3.81)
					(name "~"
						(effects
							(font
								(size 1.27 1.27)
							)
						)
					)
					(number "32"
						(effects
							(font
								(size 1.27 1.27)
							)
						)
					)
				)
				(pin passive line
					(at 0 -81.28 0)
					(length 3.81)
					(name "~"
						(effects
							(font
								(size 1.27 1.27)
							)
						)
					)
					(number "33"
						(effects
							(font
								(size 1.27 1.27)
							)
						)
					)
				)
				(pin passive line
					(at 0 -83.82 0)
					(length 3.81)
					(name "~"
						(effects
							(font
								(size 1.27 1.27)
							)
						)
					)
					(number "34"
						(effects
							(font
								(size 1.27 1.27)
							)
						)
					)
				)
				(pin passive line
					(at 0 -86.36 0)
					(length 3.81)
					(name "~"
						(effects
							(font
								(size 1.27 1.27)
							)
						)
					)
					(number "35"
						(effects
							(font
								(size 1.27 1.27)
							)
						)
					)
				)
				(pin passive line
					(at 0 -88.9 0)
					(length 3.81)
					(name "~"
						(effects
							(font
								(size 1.27 1.27)
							)
						)
					)
					(number "36"
						(effects
							(font
								(size 1.27 1.27)
							)
						)
					)
				)
				(pin passive line
					(at 0 -91.44 0)
					(length 3.81)
					(name "~"
						(effects
							(font
								(size 1.27 1.27)
							)
						)
					)
					(number "37"
						(effects
							(font
								(size 1.27 1.27)
							)
						)
					)
				)
				(pin passive line
					(at 0 -93.98 0)
					(length 3.81)
					(name "~"
						(effects
							(font
								(size 1.27 1.27)
							)
						)
					)
					(number "38"
						(effects
							(font
								(size 1.27 1.27)
							)
						)
					)
				)
				(pin passive line
					(at 0 -96.52 0)
					(length 3.81)
					(name "~"
						(effects
							(font
								(size 1.27 1.27)
							)
						)
					)
					(number "39"
						(effects
							(font
								(size 1.27 1.27)
							)
						)
					)
				)
				(pin passive line
					(at 0 -99.06 0)
					(length 3.81)
					(name "~"
						(effects
							(font
								(size 1.27 1.27)
							)
						)
					)
					(number "40"
						(effects
							(font
								(size 1.27 1.27)
							)
						)
					)
				)
				(pin passive line
					(at 0 -101.6 0)
					(length 3.81)
					(name "~"
						(effects
							(font
								(size 1.27 1.27)
							)
						)
					)
					(number "41"
						(effects
							(font
								(size 1.27 1.27)
							)
						)
					)
				)
				(pin passive line
					(at 0 -104.14 0)
					(length 3.81)
					(name "~"
						(effects
							(font
								(size 1.27 1.27)
							)
						)
					)
					(number "42"
						(effects
							(font
								(size 1.27 1.27)
							)
						)
					)
				)
				(pin passive line
					(at 0 -106.68 0)
					(length 3.81)
					(name "~"
						(effects
							(font
								(size 1.27 1.27)
							)
						)
					)
					(number "43"
						(effects
							(font
								(size 1.27 1.27)
							)
						)
					)
				)
				(pin passive line
					(at 0 -109.22 0)
					(length 3.81)
					(name "~"
						(effects
							(font
								(size 1.27 1.27)
							)
						)
					)
					(number "44"
						(effects
							(font
								(size 1.27 1.27)
							)
						)
					)
				)
				(pin passive line
					(at 0 -111.76 0)
					(length 3.81)
					(name "~"
						(effects
							(font
								(size 1.27 1.27)
							)
						)
					)
					(number "45"
						(effects
							(font
								(size 1.27 1.27)
							)
						)
					)
				)
				(pin passive line
					(at 0 -114.3 0)
					(length 3.81)
					(name "~"
						(effects
							(font
								(size 1.27 1.27)
							)
						)
					)
					(number "46"
						(effects
							(font
								(size 1.27 1.27)
							)
						)
					)
				)
				(pin passive line
					(at 0 -116.84 0)
					(length 3.81)
					(name "~"
						(effects
							(font
								(size 1.27 1.27)
							)
						)
					)
					(number "47"
						(effects
							(font
								(size 1.27 1.27)
							)
						)
					)
				)
				(pin passive line
					(at 0 -119.38 0)
					(length 3.81)
					(name "~"
						(effects
							(font
								(size 1.27 1.27)
							)
						)
					)
					(number "48"
						(effects
							(font
								(size 1.27 1.27)
							)
						)
					)
				)
				(pin passive line
					(at 0 -121.92 0)
					(length 3.81)
					(name "~"
						(effects
							(font
								(size 1.27 1.27)
							)
						)
					)
					(number "49"
						(effects
							(font
								(size 1.27 1.27)
							)
						)
					)
				)
				(pin passive line
					(at 0 -124.46 0)
					(length 3.81)
					(name "~"
						(effects
							(font
								(size 1.27 1.27)
							)
						)
					)
					(number "50"
						(effects
							(font
								(size 1.27 1.27)
							)
						)
					)
				)
				(pin passive line
					(at 0 -127 0)
					(length 3.81)
					(name "MP"
						(effects
							(font
								(size 1.27 1.27)
							)
						)
					)
					(number "MP1"
						(effects
							(font
								(size 1.27 1.27)
							)
						)
					)
				)
				(pin passive line
					(at 0 -129.54 0)
					(length 3.81)
					(name "MP"
						(effects
							(font
								(size 1.27 1.27)
							)
						)
					)
					(number "MP2"
						(effects
							(font
								(size 1.27 1.27)
							)
						)
					)
				)
			)
		)
	(symbol "antmicroFerriteBeadsandChips:FB_120Z_1.3A_Murata-BLM15PD_0402"
			(pin_numbers
				(hide yes)
			)
			(pin_names
				(hide yes)
			)
			(exclude_from_sim no)
			(in_bom yes)
			(on_board yes)
			(property "Reference" "FB"
				(at 13.97 0 0)
				(effects
					(font
						(size 1.27 1.27)
						(thickness 0.15)
					)
					(justify left bottom)
				)
			)
			(property "Value" "FB_120Z_1.3A_Murata-BLM15PD_0402"
				(at 13.97 -2.54 0)
				(effects
					(font
						(size 1.27 1.27)
						(thickness 0.15)
					)
					(justify left bottom)
					(hide yes)
				)
			)
			(property "Footprint" "antmicro-footprints:FB_0402_1005Metric"
				(at 13.97 -7.62 0)
				(effects
					(font
						(size 1.27 1.27)
						(thickness 0.15)
					)
					(justify left bottom)
					(hide yes)
				)
			)
			(property "Datasheet" "https://www.murata.com/en-us/products/productdata/8796740059166/ENFA0018.pdf"
				(at 13.97 -10.16 0)
				(effects
					(font
						(size 1.27 1.27)
						(thickness 0.15)
					)
					(justify left bottom)
					(hide yes)
				)
			)
			(property "Description" "Ferrite Bead, 0402 [1005 Metric], 120 ohm, 1.3 A, BLM15PD, 0.09 ohm, ± 25%, DC power line"
				(at 0 0 0)
				(effects
					(font
						(size 1.27 1.27)
					)
					(hide yes)
				)
			)
			(property "Val" "120Z/1.3A"
				(at 13.97 -5.08 0)
				(effects
					(font
						(size 1.27 1.27)
					)
					(justify left bottom)
				)
			)
			(property "MPN" "BLM15PD121SN1D"
				(at 13.97 -12.7 0)
				(effects
					(font
						(size 1.27 1.27)
						(thickness 0.15)
					)
					(justify left bottom)
					(hide yes)
				)
			)
			(property "Manufacturer" "Murata"
				(at 13.97 -15.24 0)
				(effects
					(font
						(size 1.27 1.27)
						(thickness 0.15)
					)
					(justify left bottom)
					(hide yes)
				)
			)
			(property "Current" ""
				(at 20.32 -22.86 0)
				(effects
					(font
						(size 1.27 1.27)
						(thickness 0.15)
					)
					(justify left bottom)
					(hide yes)
				)
			)
			(property "Author" "Antmicro"
				(at 13.97 -17.78 0)
				(effects
					(font
						(size 1.27 1.27)
						(thickness 0.15)
					)
					(justify left bottom)
					(hide yes)
				)
			)
			(property "License" "Apache-2.0"
				(at 13.97 -20.32 0)
				(effects
					(font
						(size 1.27 1.27)
						(thickness 0.15)
					)
					(justify left bottom)
					(hide yes)
				)
			)
			(property "ki_keywords" "0402, SMT, FERRITE BEAD, PASSIVE"
				(at 0 0 0)
				(effects
					(font
						(size 1.27 1.27)
					)
					(hide yes)
				)
			)
			(symbol "FB_120Z_1.3A_Murata-BLM15PD_0402_0_1"
				(polyline
					(pts
						(xy 1.651 0) (xy 1.2446 0)
					)
					(stroke
						(width 0)
						(type default)
					)
					(fill
						(type none)
					)
				)
				(polyline
					(pts
						(xy 2.2606 -1.8288) (xy 1.0414 -1.1176) (xy 2.7432 1.8288) (xy 3.9624 1.1176) (xy 2.2606 -1.8288)
					)
					(stroke
						(width 0)
						(type default)
					)
					(fill
						(type none)
					)
				)
				(polyline
					(pts
						(xy 3.81 0) (xy 3.3274 0)
					)
					(stroke
						(width 0)
						(type default)
					)
					(fill
						(type none)
					)
				)
			)
			(symbol "FB_120Z_1.3A_Murata-BLM15PD_0402_1_1"
				(pin passive line
					(at 0 0 0)
					(length 1.27)
					(name "~"
						(effects
							(font
								(size 1.27 1.27)
							)
						)
					)
					(number "1"
						(effects
							(font
								(size 1.27 1.27)
							)
						)
					)
				)
				(pin passive line
					(at 5.08 0 180)
					(length 1.27)
					(name "~"
						(effects
							(font
								(size 1.27 1.27)
							)
						)
					)
					(number "2"
						(effects
							(font
								(size 1.27 1.27)
							)
						)
					)
				)
			)
		)
	(symbol "antmicroFerriteBeadsandChips:FB_220Z_2.2A_TDK-MPZ_0603"
			(pin_numbers
				(hide yes)
			)
			(pin_names
				(hide yes)
			)
			(exclude_from_sim no)
			(in_bom yes)
			(on_board yes)
			(property "Reference" "FB"
				(at 13.97 0 0)
				(effects
					(font
						(size 1.27 1.27)
					)
					(justify left bottom)
				)
			)
			(property "Value" "FB_220Z_2.2A_TDK-MPZ_0603"
				(at 13.97 -2.54 0)
				(effects
					(font
						(size 1.27 1.27)
						(thickness 0.15)
					)
					(justify left bottom)
					(hide yes)
				)
			)
			(property "Footprint" "antmicro-footprints:FB_0603_1608Metric"
				(at 13.97 -7.62 0)
				(effects
					(font
						(size 1.27 1.27)
						(thickness 0.15)
					)
					(justify left bottom)
					(hide yes)
				)
			)
			(property "Datasheet" "https://product.tdk.com/info/en/catalog/datasheets/beads_commercial_power_mpz1608_en.pdf"
				(at 13.97 -10.16 0)
				(effects
					(font
						(size 1.27 1.27)
						(thickness 0.15)
					)
					(justify left bottom)
					(hide yes)
				)
			)
			(property "Description" "Ferrite Bead, 0603 [1608 Metric], 220 ohm, 2.2 A, MPZ, 0.05 ohm, ± 25%, DC power line"
				(at 0 0 0)
				(effects
					(font
						(size 1.27 1.27)
					)
					(hide yes)
				)
			)
			(property "Val" "220Z/2.2A"
				(at 13.97 -5.08 0)
				(effects
					(font
						(size 1.27 1.27)
					)
					(justify left bottom)
				)
			)
			(property "MPN" "MPZ1608S221ATA00"
				(at 13.97 -12.7 0)
				(effects
					(font
						(size 1.27 1.27)
						(thickness 0.15)
					)
					(justify left bottom)
					(hide yes)
				)
			)
			(property "Manufacturer" "TDK"
				(at 13.97 -15.24 0)
				(effects
					(font
						(size 1.27 1.27)
						(thickness 0.15)
					)
					(justify left bottom)
					(hide yes)
				)
			)
			(property "Current" ""
				(at 20.32 -22.86 0)
				(effects
					(font
						(size 1.27 1.27)
						(thickness 0.15)
					)
					(justify left bottom)
					(hide yes)
				)
			)
			(property "Author" "Antmicro"
				(at 13.97 -17.78 0)
				(effects
					(font
						(size 1.27 1.27)
						(thickness 0.15)
					)
					(justify left bottom)
					(hide yes)
				)
			)
			(property "License" "Apache-2.0"
				(at 13.97 -20.32 0)
				(effects
					(font
						(size 1.27 1.27)
						(thickness 0.15)
					)
					(justify left bottom)
					(hide yes)
				)
			)
			(property "ki_keywords" "0603, SMT, FERRITE BEAD, PASSIVE"
				(at 0 0 0)
				(effects
					(font
						(size 1.27 1.27)
					)
					(hide yes)
				)
			)
			(symbol "FB_220Z_2.2A_TDK-MPZ_0603_0_1"
				(polyline
					(pts
						(xy 1.651 0) (xy 1.2446 0)
					)
					(stroke
						(width 0)
						(type default)
					)
					(fill
						(type none)
					)
				)
				(polyline
					(pts
						(xy 2.2606 -1.8288) (xy 1.0414 -1.1176) (xy 2.7432 1.8288) (xy 3.9624 1.1176) (xy 2.2606 -1.8288)
					)
					(stroke
						(width 0)
						(type default)
					)
					(fill
						(type none)
					)
				)
				(polyline
					(pts
						(xy 3.81 0) (xy 3.3274 0)
					)
					(stroke
						(width 0)
						(type default)
					)
					(fill
						(type none)
					)
				)
			)
			(symbol "FB_220Z_2.2A_TDK-MPZ_0603_1_1"
				(pin passive line
					(at 0 0 0)
					(length 1.27)
					(name "~"
						(effects
							(font
								(size 1.27 1.27)
							)
						)
					)
					(number "1"
						(effects
							(font
								(size 1.27 1.27)
							)
						)
					)
				)
				(pin passive line
					(at 5.08 0 180)
					(length 1.27)
					(name "~"
						(effects
							(font
								(size 1.27 1.27)
							)
						)
					)
					(number "2"
						(effects
							(font
								(size 1.27 1.27)
							)
						)
					)
				)
			)
		)
	(symbol "antmicroFixedInductors:L_160n_0.28A_0603"
			(pin_numbers
				(hide yes)
			)
			(pin_names
				(hide yes)
			)
			(exclude_from_sim no)
			(in_bom yes)
			(on_board yes)
			(property "Reference" "L"
				(at 13.97 0 0)
				(effects
					(font
						(size 1.27 1.27)
						(thickness 0.15)
					)
					(justify left bottom)
				)
			)
			(property "Value" "L_160n_0.28A_0603"
				(at 13.97 -2.54 0)
				(effects
					(font
						(size 1.27 1.27)
						(thickness 0.15)
					)
					(justify left bottom)
					(hide yes)
				)
			)
			(property "Footprint" "antmicro-footprints:L_TE_0603_1811Metric"
				(at 13.97 -7.62 0)
				(effects
					(font
						(size 1.27 1.27)
						(thickness 0.15)
					)
					(justify left bottom)
					(hide yes)
				)
			)
			(property "Datasheet" "https://www.te.com/commerce/DocumentDelivery/DDEController?Action=showdoc&DocId=Data+Sheet%7F1773163%7FE%7Fpdf%7FEnglish%7FENG_DS_1773163_E.pdf"
				(at 13.97 -10.16 0)
				(effects
					(font
						(size 1.27 1.27)
						(thickness 0.15)
					)
					(justify left bottom)
					(hide yes)
				)
			)
			(property "Description" "RF Inductor - 160 nH, 5%, 280 mA, 0603"
				(at 13.97 -30.48 0)
				(effects
					(font
						(size 1.27 1.27)
					)
					(justify left bottom)
					(hide yes)
				)
			)
			(property "Val" "160 nH"
				(at 13.97 -5.08 0)
				(effects
					(font
						(size 1.27 1.27)
						(thickness 0.15)
					)
					(justify left bottom)
				)
			)
			(property "Manufacturer" "TE Connectivity"
				(at 13.97 -12.7 0)
				(effects
					(font
						(size 1.27 1.27)
						(thickness 0.15)
					)
					(justify left bottom)
					(hide yes)
				)
			)
			(property "MPN" "36501JR16JTDG"
				(at 13.97 -15.24 0)
				(effects
					(font
						(size 1.27 1.27)
						(thickness 0.15)
					)
					(justify left bottom)
					(hide yes)
				)
			)
			(property "ISat" ""
				(at 13.97 -16.51 0)
				(effects
					(font
						(size 1.27 1.27)
					)
					(justify left)
					(hide yes)
				)
			)
			(property "IMax" "0.28 A"
				(at 13.97 -20.32 0)
				(effects
					(font
						(size 1.27 1.27)
						(thickness 0.15)
					)
					(justify left bottom)
					(hide yes)
				)
			)
			(property "Size" "1.8 x 1.12"
				(at 13.97 -22.86 0)
				(effects
					(font
						(size 1.27 1.27)
						(thickness 0.15)
					)
					(justify left bottom)
					(hide yes)
				)
			)
			(property "Author" "Antmicro"
				(at 13.97 -25.4 0)
				(effects
					(font
						(size 1.27 1.27)
						(thickness 0.15)
					)
					(justify left bottom)
					(hide yes)
				)
			)
			(property "License" "Apache-2.0"
				(at 13.97 -27.94 0)
				(effects
					(font
						(size 1.27 1.27)
						(thickness 0.15)
					)
					(justify left bottom)
					(hide yes)
				)
			)
			(property "ki_keywords" "INDUCTOR, RF, PASSIVE"
				(at 0 0 0)
				(effects
					(font
						(size 1.27 1.27)
					)
					(hide yes)
				)
			)
			(symbol "L_160n_0.28A_0603_0_1"
				(arc
					(start 0.508 0)
					(mid 1.016 0.5058)
					(end 1.524 0)
					(stroke
						(width 0)
						(type default)
					)
					(fill
						(type none)
					)
				)
				(arc
					(start 1.524 0)
					(mid 2.032 0.5058)
					(end 2.54 0)
					(stroke
						(width 0)
						(type default)
					)
					(fill
						(type none)
					)
				)
				(arc
					(start 2.54 0)
					(mid 3.048 0.5058)
					(end 3.556 0)
					(stroke
						(width 0)
						(type default)
					)
					(fill
						(type none)
					)
				)
				(arc
					(start 3.556 0)
					(mid 4.064 0.5058)
					(end 4.572 0)
					(stroke
						(width 0)
						(type default)
					)
					(fill
						(type none)
					)
				)
			)
			(symbol "L_160n_0.28A_0603_1_1"
				(pin passive line
					(at 0 0 0)
					(length 0.508)
					(name "~"
						(effects
							(font
								(size 1.27 1.27)
							)
						)
					)
					(number "1"
						(effects
							(font
								(size 1.27 1.27)
							)
						)
					)
				)
				(pin passive line
					(at 5.08 0 180)
					(length 0.508)
					(name "~"
						(effects
							(font
								(size 1.27 1.27)
							)
						)
					)
					(number "2"
						(effects
							(font
								(size 1.27 1.27)
							)
						)
					)
				)
			)
		)
	(symbol "antmicroFixedInductors:L_1u8_14A_Coilcraft-XAL6030"
			(pin_numbers
				(hide yes)
			)
			(pin_names
				(hide yes)
			)
			(exclude_from_sim no)
			(in_bom yes)
			(on_board yes)
			(property "Reference" "L"
				(at 15.24 -5.08 0)
				(effects
					(font
						(size 1.27 1.27)
						(thickness 0.15)
					)
					(justify left bottom)
				)
			)
			(property "Value" "L_1u8_14A_Coilcraft-XAL6030"
				(at 15.24 -10.16 0)
				(effects
					(font
						(size 1.27 1.27)
						(thickness 0.15)
					)
					(justify left bottom)
					(hide yes)
				)
			)
			(property "Footprint" "antmicro-footprints:L_Coilcraft-XAL6030"
				(at 15.24 -12.7 0)
				(effects
					(font
						(size 1.27 1.27)
						(thickness 0.15)
					)
					(justify left bottom)
					(hide yes)
				)
			)
			(property "Datasheet" "https://www.mouser.com/datasheet/2/597/xal60xx-270658.pdf"
				(at 15.24 -15.24 0)
				(effects
					(font
						(size 1.27 1.27)
						(thickness 0.15)
					)
					(justify left bottom)
					(hide yes)
				)
			)
			(property "Description" "Power Inductor (SMT), 1.8 µH, 14 A, Shielded, 18.2 A, XAL6030"
				(at 0 0 0)
				(effects
					(font
						(size 1.27 1.27)
					)
					(hide yes)
				)
			)
			(property "Manufacturer" "Coilcraft"
				(at 15.24 -17.78 0)
				(effects
					(font
						(size 1.27 1.27)
						(thickness 0.15)
					)
					(justify left bottom)
					(hide yes)
				)
			)
			(property "MPN" "XAL6030-182MEC"
				(at 15.24 -20.32 0)
				(effects
					(font
						(size 1.27 1.27)
						(thickness 0.15)
					)
					(justify left bottom)
					(hide yes)
				)
			)
			(property "ISat" "18.2 A"
				(at 15.24 -22.86 0)
				(effects
					(font
						(size 1.27 1.27)
						(thickness 0.15)
					)
					(justify left bottom)
					(hide yes)
				)
			)
			(property "IMax" "14 A"
				(at 15.24 -25.4 0)
				(effects
					(font
						(size 1.27 1.27)
						(thickness 0.15)
					)
					(justify left bottom)
					(hide yes)
				)
			)
			(property "Size" "6.36x6.56"
				(at 15.24 -27.94 0)
				(effects
					(font
						(size 1.27 1.27)
						(thickness 0.15)
					)
					(justify left bottom)
					(hide yes)
				)
			)
			(property "Val" "1.8u/14A"
				(at 15.24 -7.62 0)
				(effects
					(font
						(size 1.27 1.27)
						(thickness 0.15)
					)
					(justify left bottom)
				)
			)
			(property "Author" "Antmicro"
				(at 15.24 -30.48 0)
				(effects
					(font
						(size 1.27 1.27)
						(thickness 0.15)
					)
					(justify left bottom)
					(hide yes)
				)
			)
			(property "License" "Apache-2.0"
				(at 15.24 -33.02 0)
				(effects
					(font
						(size 1.27 1.27)
						(thickness 0.15)
					)
					(justify left bottom)
					(hide yes)
				)
			)
			(property "ki_keywords" "SMT, INDUCTOR, PASSIVE"
				(at 0 0 0)
				(effects
					(font
						(size 1.27 1.27)
					)
					(hide yes)
				)
			)
			(symbol "L_1u8_14A_Coilcraft-XAL6030_0_1"
				(arc
					(start 0.508 0)
					(mid 1.016 0.5058)
					(end 1.524 0)
					(stroke
						(width 0)
						(type default)
					)
					(fill
						(type none)
					)
				)
				(arc
					(start 1.524 0)
					(mid 2.032 0.5058)
					(end 2.54 0)
					(stroke
						(width 0)
						(type default)
					)
					(fill
						(type none)
					)
				)
				(arc
					(start 2.54 0)
					(mid 3.048 0.5058)
					(end 3.556 0)
					(stroke
						(width 0)
						(type default)
					)
					(fill
						(type none)
					)
				)
				(arc
					(start 3.556 0)
					(mid 4.064 0.5058)
					(end 4.572 0)
					(stroke
						(width 0)
						(type default)
					)
					(fill
						(type none)
					)
				)
			)
			(symbol "L_1u8_14A_Coilcraft-XAL6030_1_1"
				(pin passive line
					(at 0 0 0)
					(length 0.508)
					(name "~"
						(effects
							(font
								(size 1.27 1.27)
							)
						)
					)
					(number "1"
						(effects
							(font
								(size 1.27 1.27)
							)
						)
					)
				)
				(pin passive line
					(at 5.08 0 180)
					(length 0.508)
					(name "~"
						(effects
							(font
								(size 1.27 1.27)
							)
						)
					)
					(number "2"
						(effects
							(font
								(size 1.27 1.27)
							)
						)
					)
				)
			)
		)
	(symbol "antmicroFixedInductors:L_1u_5.5A_Bourns-SRP3212A"
			(pin_numbers
				(hide yes)
			)
			(pin_names
				(hide yes)
			)
			(exclude_from_sim no)
			(in_bom yes)
			(on_board yes)
			(property "Reference" "L"
				(at 13.97 0 0)
				(effects
					(font
						(size 1.27 1.27)
						(thickness 0.15)
					)
					(justify left bottom)
				)
			)
			(property "Value" "L_1u_5.5A_Bourns-SRP3212A"
				(at 13.97 -2.54 0)
				(effects
					(font
						(size 1.27 1.27)
						(thickness 0.15)
					)
					(justify left bottom)
					(hide yes)
				)
			)
			(property "Footprint" "antmicro-footprints:L_Bourns-SRP3212A"
				(at 13.97 -7.62 0)
				(effects
					(font
						(size 1.27 1.27)
						(thickness 0.15)
					)
					(justify left bottom)
					(hide yes)
				)
			)
			(property "Datasheet" "https://www.mouser.com/datasheet/2/54/SRP3212A-3011944.pdf"
				(at 13.97 -10.16 0)
				(effects
					(font
						(size 1.27 1.27)
						(thickness 0.15)
					)
					(justify left bottom)
					(hide yes)
				)
			)
			(property "Description" "Power Inductor (SMD), 1 µH, 5.5 A, Shielded, 6.5 A, SRP3212 Series"
				(at 0 0 0)
				(effects
					(font
						(size 1.27 1.27)
					)
					(hide yes)
				)
			)
			(property "Val" "1u/5.5A"
				(at 13.97 -5.08 0)
				(effects
					(font
						(size 1.27 1.27)
						(thickness 0.15)
					)
					(justify left bottom)
				)
			)
			(property "Manufacturer" "Bourns"
				(at 13.97 -12.7 0)
				(effects
					(font
						(size 1.27 1.27)
						(thickness 0.15)
					)
					(justify left bottom)
					(hide yes)
				)
			)
			(property "MPN" "SRP3212A-1R0M"
				(at 13.97 -15.24 0)
				(effects
					(font
						(size 1.27 1.27)
						(thickness 0.15)
					)
					(justify left bottom)
					(hide yes)
				)
			)
			(property "ISat" "6.5 A"
				(at 13.97 -16.51 0)
				(effects
					(font
						(size 1.27 1.27)
					)
					(justify left)
					(hide yes)
				)
			)
			(property "IMax" "5.5 A"
				(at 13.97 -20.32 0)
				(effects
					(font
						(size 1.27 1.27)
						(thickness 0.15)
					)
					(justify left bottom)
					(hide yes)
				)
			)
			(property "Size" "3.2x2.5"
				(at 13.97 -22.86 0)
				(effects
					(font
						(size 1.27 1.27)
						(thickness 0.15)
					)
					(justify left bottom)
					(hide yes)
				)
			)
			(property "Author" "Antmicro"
				(at 13.97 -25.4 0)
				(effects
					(font
						(size 1.27 1.27)
						(thickness 0.15)
					)
					(justify left bottom)
					(hide yes)
				)
			)
			(property "License" "Apache-2.0"
				(at 13.97 -27.94 0)
				(effects
					(font
						(size 1.27 1.27)
						(thickness 0.15)
					)
					(justify left bottom)
					(hide yes)
				)
			)
			(property "ki_keywords" "SMT, INDUCTOR, PASSIVE"
				(at 0 0 0)
				(effects
					(font
						(size 1.27 1.27)
					)
					(hide yes)
				)
			)
			(symbol "L_1u_5.5A_Bourns-SRP3212A_0_1"
				(arc
					(start 0.508 0)
					(mid 1.016 0.5058)
					(end 1.524 0)
					(stroke
						(width 0)
						(type default)
					)
					(fill
						(type none)
					)
				)
				(arc
					(start 1.524 0)
					(mid 2.032 0.5058)
					(end 2.54 0)
					(stroke
						(width 0)
						(type default)
					)
					(fill
						(type none)
					)
				)
				(arc
					(start 2.54 0)
					(mid 3.048 0.5058)
					(end 3.556 0)
					(stroke
						(width 0)
						(type default)
					)
					(fill
						(type none)
					)
				)
				(arc
					(start 3.556 0)
					(mid 4.064 0.5058)
					(end 4.572 0)
					(stroke
						(width 0)
						(type default)
					)
					(fill
						(type none)
					)
				)
			)
			(symbol "L_1u_5.5A_Bourns-SRP3212A_1_1"
				(pin passive line
					(at 0 0 0)
					(length 0.508)
					(name "~"
						(effects
							(font
								(size 1.27 1.27)
							)
						)
					)
					(number "1"
						(effects
							(font
								(size 1.27 1.27)
							)
						)
					)
				)
				(pin passive line
					(at 5.08 0 180)
					(length 0.508)
					(name "~"
						(effects
							(font
								(size 1.27 1.27)
							)
						)
					)
					(number "2"
						(effects
							(font
								(size 1.27 1.27)
							)
						)
					)
				)
			)
		)
	(symbol "antmicroInterfaceControllers:FT4233HPQ"
			(exclude_from_sim no)
			(in_bom yes)
			(on_board yes)
			(property "Reference" "U"
				(at 45.72 -2.54 0)
				(effects
					(font
						(size 1.27 1.27)
						(thickness 0.15)
					)
					(justify left bottom)
				)
			)
			(property "Value" "FT4233HPQ"
				(at 45.72 -7.62 0)
				(effects
					(font
						(size 1.27 1.27)
						(thickness 0.15)
					)
					(justify left bottom)
					(hide yes)
				)
			)
			(property "Footprint" "antmicro-footprints:QFN-76-1EP_9x9mm_P0.4mm_EP6.3x6.3mm"
				(at 45.72 -10.16 0)
				(effects
					(font
						(size 1.27 1.27)
						(thickness 0.15)
					)
					(justify left bottom)
					(hide yes)
				)
			)
			(property "Datasheet" "https://ftdichip.com/wp-content/uploads/2023/09/DS_FT4233HP-v1.5.pdf"
				(at 45.72 -12.7 0)
				(effects
					(font
						(size 1.27 1.27)
						(thickness 0.15)
					)
					(justify left bottom)
					(hide yes)
				)
			)
			(property "Description" "USB Hi-Speed/Quad Channel Serial UART/JTAG/SPI/I2C,Dual PD Ports IC"
				(at 0 0 0)
				(effects
					(font
						(size 1.27 1.27)
					)
					(hide yes)
				)
			)
			(property "MPN" "FT4233HPQ-REEL"
				(at 45.72 -5.08 0)
				(effects
					(font
						(size 1.27 1.27)
						(thickness 0.15)
					)
					(justify left bottom)
				)
			)
			(property "Manufacturer" "FTDI Chip"
				(at 45.72 -15.24 0)
				(effects
					(font
						(size 1.27 1.27)
						(thickness 0.15)
					)
					(justify left bottom)
					(hide yes)
				)
			)
			(property "License" "Apache-2.0"
				(at 45.72 -17.78 0)
				(effects
					(font
						(size 1.27 1.27)
						(thickness 0.15)
					)
					(justify left bottom)
					(hide yes)
				)
			)
			(property "Author" "Antmicro"
				(at 45.72 -20.32 0)
				(effects
					(font
						(size 1.27 1.27)
						(thickness 0.15)
					)
					(justify left bottom)
					(hide yes)
				)
			)
			(property "ki_keywords" "SMT, INTERFACE, IC, CONTROLLER, USB, UART, I2C, SPI"
				(at 0 0 0)
				(effects
					(font
						(size 1.27 1.27)
					)
					(hide yes)
				)
			)
			(symbol "FT4233HPQ_1_1"
				(rectangle
					(start 2.54 2.54)
					(end 29.21 -106.68)
					(stroke
						(width 0.254)
						(type default)
					)
					(fill
						(type background)
					)
				)
				(pin input line
					(at 0 0 0)
					(length 2.54)
					(name "VREGIN"
						(effects
							(font
								(size 1.27 1.27)
							)
						)
					)
					(number "32"
						(effects
							(font
								(size 1.27 1.27)
							)
						)
					)
				)
				(pin power_in line
					(at 0 -2.54 0)
					(length 2.54)
					(name "VCCIO"
						(effects
							(font
								(size 1.27 1.27)
							)
						)
					)
					(number "12"
						(effects
							(font
								(size 1.27 1.27)
							)
						)
					)
				)
				(pin passive line
					(at 0 -2.54 0)
					(length 2.54)
					(hide yes)
					(name "VCCIO"
						(effects
							(font
								(size 1.27 1.27)
							)
						)
					)
					(number "28"
						(effects
							(font
								(size 1.27 1.27)
							)
						)
					)
				)
				(pin passive line
					(at 0 -2.54 0)
					(length 2.54)
					(hide yes)
					(name "VCCIO"
						(effects
							(font
								(size 1.27 1.27)
							)
						)
					)
					(number "41"
						(effects
							(font
								(size 1.27 1.27)
							)
						)
					)
				)
				(pin passive line
					(at 0 -2.54 0)
					(length 2.54)
					(hide yes)
					(name "VCCIO"
						(effects
							(font
								(size 1.27 1.27)
							)
						)
					)
					(number "54"
						(effects
							(font
								(size 1.27 1.27)
							)
						)
					)
				)
				(pin power_in line
					(at 0 -5.08 0)
					(length 2.54)
					(name "VCC_USB"
						(effects
							(font
								(size 1.27 1.27)
							)
						)
					)
					(number "62"
						(effects
							(font
								(size 1.27 1.27)
							)
						)
					)
				)
				(pin power_in line
					(at 0 -7.62 0)
					(length 2.54)
					(name "VCC_PD"
						(effects
							(font
								(size 1.27 1.27)
							)
						)
					)
					(number "66"
						(effects
							(font
								(size 1.27 1.27)
							)
						)
					)
				)
				(pin power_in line
					(at 0 -10.16 0)
					(length 2.54)
					(name "PD1_VCONN"
						(effects
							(font
								(size 1.27 1.27)
							)
						)
					)
					(number "69"
						(effects
							(font
								(size 1.27 1.27)
							)
						)
					)
				)
				(pin input line
					(at 0 -13.97 0)
					(length 2.54)
					(name "FSOURCE"
						(effects
							(font
								(size 1.27 1.27)
							)
						)
					)
					(number "34"
						(effects
							(font
								(size 1.27 1.27)
							)
						)
					)
				)
				(pin input line
					(at 0 -16.51 0)
					(length 2.54)
					(name "VPP"
						(effects
							(font
								(size 1.27 1.27)
							)
						)
					)
					(number "35"
						(effects
							(font
								(size 1.27 1.27)
							)
						)
					)
				)
				(pin bidirectional line
					(at 0 -20.32 0)
					(length 2.54)
					(name "DP"
						(effects
							(font
								(size 1.27 1.27)
							)
						)
					)
					(number "64"
						(effects
							(font
								(size 1.27 1.27)
							)
						)
					)
				)
				(pin bidirectional line
					(at 0 -22.86 0)
					(length 2.54)
					(name "DM"
						(effects
							(font
								(size 1.27 1.27)
							)
						)
					)
					(number "63"
						(effects
							(font
								(size 1.27 1.27)
							)
						)
					)
				)
				(pin input line
					(at 0 -26.67 0)
					(length 2.54)
					(name "PD1_SVBUS"
						(effects
							(font
								(size 1.27 1.27)
							)
						)
					)
					(number "68"
						(effects
							(font
								(size 1.27 1.27)
							)
						)
					)
				)
				(pin bidirectional line
					(at 0 -29.21 0)
					(length 2.54)
					(name "PD1_CC1"
						(effects
							(font
								(size 1.27 1.27)
							)
						)
					)
					(number "70"
						(effects
							(font
								(size 1.27 1.27)
							)
						)
					)
				)
				(pin bidirectional line
					(at 0 -31.75 0)
					(length 2.54)
					(name "PD1_CC2"
						(effects
							(font
								(size 1.27 1.27)
							)
						)
					)
					(number "67"
						(effects
							(font
								(size 1.27 1.27)
							)
						)
					)
				)
				(pin input line
					(at 0 -35.56 0)
					(length 2.54)
					(name "PD2_SVBUS"
						(effects
							(font
								(size 1.27 1.27)
							)
						)
					)
					(number "72"
						(effects
							(font
								(size 1.27 1.27)
							)
						)
					)
				)
				(pin bidirectional line
					(at 0 -38.1 0)
					(length 2.54)
					(name "PD2_CC1"
						(effects
							(font
								(size 1.27 1.27)
							)
						)
					)
					(number "71"
						(effects
							(font
								(size 1.27 1.27)
							)
						)
					)
				)
				(pin bidirectional line
					(at 0 -40.64 0)
					(length 2.54)
					(name "PD2_CC2"
						(effects
							(font
								(size 1.27 1.27)
							)
						)
					)
					(number "73"
						(effects
							(font
								(size 1.27 1.27)
							)
						)
					)
				)
				(pin output clock
					(at 0 -45.72 0)
					(length 2.54)
					(name "EECLK"
						(effects
							(font
								(size 1.27 1.27)
							)
						)
					)
					(number "1"
						(effects
							(font
								(size 1.27 1.27)
							)
						)
					)
				)
				(pin bidirectional line
					(at 0 -48.26 0)
					(length 2.54)
					(name "EEDATA"
						(effects
							(font
								(size 1.27 1.27)
							)
						)
					)
					(number "2"
						(effects
							(font
								(size 1.27 1.27)
							)
						)
					)
				)
				(pin bidirectional line
					(at 0 -50.8 0)
					(length 2.54)
					(name "EECS"
						(effects
							(font
								(size 1.27 1.27)
							)
						)
					)
					(number "76"
						(effects
							(font
								(size 1.27 1.27)
							)
						)
					)
				)
				(pin input line
					(at 0 -68.58 0)
					(length 2.54)
					(name "~{RESET}"
						(effects
							(font
								(size 1.27 1.27)
							)
						)
					)
					(number "4"
						(effects
							(font
								(size 1.27 1.27)
							)
						)
					)
				)
				(pin output line
					(at 0 -71.12 0)
					(length 2.54)
					(name "~{PWREN}"
						(effects
							(font
								(size 1.27 1.27)
							)
						)
					)
					(number "75"
						(effects
							(font
								(size 1.27 1.27)
							)
						)
					)
				)
				(pin output line
					(at 0 -73.66 0)
					(length 2.54)
					(name "~{SUSPEND}"
						(effects
							(font
								(size 1.27 1.27)
							)
						)
					)
					(number "45"
						(effects
							(font
								(size 1.27 1.27)
							)
						)
					)
				)
				(pin input line
					(at 0 -77.47 0)
					(length 2.54)
					(name "OSCI"
						(effects
							(font
								(size 1.27 1.27)
							)
						)
					)
					(number "29"
						(effects
							(font
								(size 1.27 1.27)
							)
						)
					)
				)
				(pin output line
					(at 0 -82.55 0)
					(length 2.54)
					(name "OSCO"
						(effects
							(font
								(size 1.27 1.27)
							)
						)
					)
					(number "30"
						(effects
							(font
								(size 1.27 1.27)
							)
						)
					)
				)
				(pin output line
					(at 0 -93.98 0)
					(length 2.54)
					(name "VREGOUT"
						(effects
							(font
								(size 1.27 1.27)
							)
						)
					)
					(number "33"
						(effects
							(font
								(size 1.27 1.27)
							)
						)
					)
				)
				(pin power_in line
					(at 0 -96.52 0)
					(length 2.54)
					(name "VCORE"
						(effects
							(font
								(size 1.27 1.27)
							)
						)
					)
					(number "10"
						(effects
							(font
								(size 1.27 1.27)
							)
						)
					)
				)
				(pin passive line
					(at 0 -96.52 0)
					(length 2.54)
					(hide yes)
					(name "VCORE"
						(effects
							(font
								(size 1.27 1.27)
							)
						)
					)
					(number "27"
						(effects
							(font
								(size 1.27 1.27)
							)
						)
					)
				)
				(pin passive line
					(at 0 -96.52 0)
					(length 2.54)
					(hide yes)
					(name "VCORE"
						(effects
							(font
								(size 1.27 1.27)
							)
						)
					)
					(number "47"
						(effects
							(font
								(size 1.27 1.27)
							)
						)
					)
				)
				(pin passive line
					(at 0 -96.52 0)
					(length 2.54)
					(hide yes)
					(name "VCORE"
						(effects
							(font
								(size 1.27 1.27)
							)
						)
					)
					(number "74"
						(effects
							(font
								(size 1.27 1.27)
							)
						)
					)
				)
				(pin input line
					(at 0 -99.06 0)
					(length 2.54)
					(name "REF"
						(effects
							(font
								(size 1.27 1.27)
							)
						)
					)
					(number "65"
						(effects
							(font
								(size 1.27 1.27)
							)
						)
					)
				)
				(pin input line
					(at 0 -101.6 0)
					(length 2.54)
					(name "TEST"
						(effects
							(font
								(size 1.27 1.27)
							)
						)
					)
					(number "3"
						(effects
							(font
								(size 1.27 1.27)
							)
						)
					)
				)
				(pin power_in line
					(at 0 -104.14 0)
					(length 2.54)
					(name "GND"
						(effects
							(font
								(size 1.27 1.27)
							)
						)
					)
					(number "11"
						(effects
							(font
								(size 1.27 1.27)
							)
						)
					)
				)
				(pin passive line
					(at 0 -104.14 0)
					(length 2.54)
					(hide yes)
					(name "GND"
						(effects
							(font
								(size 1.27 1.27)
							)
						)
					)
					(number "31"
						(effects
							(font
								(size 1.27 1.27)
							)
						)
					)
				)
				(pin passive line
					(at 0 -104.14 0)
					(length 2.54)
					(hide yes)
					(name "GND"
						(effects
							(font
								(size 1.27 1.27)
							)
						)
					)
					(number "55"
						(effects
							(font
								(size 1.27 1.27)
							)
						)
					)
				)
				(pin passive line
					(at 0 -104.14 0)
					(length 2.54)
					(hide yes)
					(name "GND"
						(effects
							(font
								(size 1.27 1.27)
							)
						)
					)
					(number "77"
						(effects
							(font
								(size 1.27 1.27)
							)
						)
					)
				)
				(pin bidirectional line
					(at 31.75 0 180)
					(length 2.54)
					(name "ADBUS0"
						(effects
							(font
								(size 1.27 1.27)
							)
						)
					)
					(number "8"
						(effects
							(font
								(size 1.27 1.27)
							)
						)
					)
				)
				(pin bidirectional line
					(at 31.75 -2.54 180)
					(length 2.54)
					(name "ADBUS1"
						(effects
							(font
								(size 1.27 1.27)
							)
						)
					)
					(number "9"
						(effects
							(font
								(size 1.27 1.27)
							)
						)
					)
				)
				(pin bidirectional line
					(at 31.75 -5.08 180)
					(length 2.54)
					(name "ADBUS2"
						(effects
							(font
								(size 1.27 1.27)
							)
						)
					)
					(number "13"
						(effects
							(font
								(size 1.27 1.27)
							)
						)
					)
				)
				(pin bidirectional line
					(at 31.75 -7.62 180)
					(length 2.54)
					(name "ADBUS3"
						(effects
							(font
								(size 1.27 1.27)
							)
						)
					)
					(number "14"
						(effects
							(font
								(size 1.27 1.27)
							)
						)
					)
				)
				(pin bidirectional line
					(at 31.75 -10.16 180)
					(length 2.54)
					(name "ADBUS4"
						(effects
							(font
								(size 1.27 1.27)
							)
						)
					)
					(number "15"
						(effects
							(font
								(size 1.27 1.27)
							)
						)
					)
				)
				(pin bidirectional line
					(at 31.75 -12.7 180)
					(length 2.54)
					(name "ADBUS5"
						(effects
							(font
								(size 1.27 1.27)
							)
						)
					)
					(number "16"
						(effects
							(font
								(size 1.27 1.27)
							)
						)
					)
				)
				(pin bidirectional line
					(at 31.75 -15.24 180)
					(length 2.54)
					(name "ADBUS6"
						(effects
							(font
								(size 1.27 1.27)
							)
						)
					)
					(number "17"
						(effects
							(font
								(size 1.27 1.27)
							)
						)
					)
				)
				(pin bidirectional line
					(at 31.75 -17.78 180)
					(length 2.54)
					(name "ADBUS7"
						(effects
							(font
								(size 1.27 1.27)
							)
						)
					)
					(number "18"
						(effects
							(font
								(size 1.27 1.27)
							)
						)
					)
				)
				(pin bidirectional line
					(at 31.75 -21.59 180)
					(length 2.54)
					(name "BDBUS0"
						(effects
							(font
								(size 1.27 1.27)
							)
						)
					)
					(number "19"
						(effects
							(font
								(size 1.27 1.27)
							)
						)
					)
				)
				(pin bidirectional line
					(at 31.75 -24.13 180)
					(length 2.54)
					(name "BDBUS1"
						(effects
							(font
								(size 1.27 1.27)
							)
						)
					)
					(number "20"
						(effects
							(font
								(size 1.27 1.27)
							)
						)
					)
				)
				(pin bidirectional line
					(at 31.75 -26.67 180)
					(length 2.54)
					(name "BDBUS2"
						(effects
							(font
								(size 1.27 1.27)
							)
						)
					)
					(number "21"
						(effects
							(font
								(size 1.27 1.27)
							)
						)
					)
				)
				(pin bidirectional line
					(at 31.75 -29.21 180)
					(length 2.54)
					(name "BDBUS3"
						(effects
							(font
								(size 1.27 1.27)
							)
						)
					)
					(number "22"
						(effects
							(font
								(size 1.27 1.27)
							)
						)
					)
				)
				(pin bidirectional line
					(at 31.75 -31.75 180)
					(length 2.54)
					(name "BDBUS4"
						(effects
							(font
								(size 1.27 1.27)
							)
						)
					)
					(number "23"
						(effects
							(font
								(size 1.27 1.27)
							)
						)
					)
				)
				(pin bidirectional line
					(at 31.75 -34.29 180)
					(length 2.54)
					(name "BDBUS5"
						(effects
							(font
								(size 1.27 1.27)
							)
						)
					)
					(number "24"
						(effects
							(font
								(size 1.27 1.27)
							)
						)
					)
				)
				(pin bidirectional line
					(at 31.75 -36.83 180)
					(length 2.54)
					(name "BDBUS6"
						(effects
							(font
								(size 1.27 1.27)
							)
						)
					)
					(number "25"
						(effects
							(font
								(size 1.27 1.27)
							)
						)
					)
				)
				(pin bidirectional line
					(at 31.75 -39.37 180)
					(length 2.54)
					(name "BDBUS7"
						(effects
							(font
								(size 1.27 1.27)
							)
						)
					)
					(number "26"
						(effects
							(font
								(size 1.27 1.27)
							)
						)
					)
				)
				(pin bidirectional line
					(at 31.75 -43.18 180)
					(length 2.54)
					(name "CDBUS0"
						(effects
							(font
								(size 1.27 1.27)
							)
						)
					)
					(number "36"
						(effects
							(font
								(size 1.27 1.27)
							)
						)
					)
				)
				(pin bidirectional line
					(at 31.75 -45.72 180)
					(length 2.54)
					(name "CDBUS1"
						(effects
							(font
								(size 1.27 1.27)
							)
						)
					)
					(number "37"
						(effects
							(font
								(size 1.27 1.27)
							)
						)
					)
				)
				(pin bidirectional line
					(at 31.75 -48.26 180)
					(length 2.54)
					(name "CDBUS2"
						(effects
							(font
								(size 1.27 1.27)
							)
						)
					)
					(number "38"
						(effects
							(font
								(size 1.27 1.27)
							)
						)
					)
				)
				(pin bidirectional line
					(at 31.75 -50.8 180)
					(length 2.54)
					(name "CDBUS3"
						(effects
							(font
								(size 1.27 1.27)
							)
						)
					)
					(number "39"
						(effects
							(font
								(size 1.27 1.27)
							)
						)
					)
				)
				(pin bidirectional line
					(at 31.75 -53.34 180)
					(length 2.54)
					(name "CDBUS4"
						(effects
							(font
								(size 1.27 1.27)
							)
						)
					)
					(number "40"
						(effects
							(font
								(size 1.27 1.27)
							)
						)
					)
				)
				(pin bidirectional line
					(at 31.75 -55.88 180)
					(length 2.54)
					(name "CDBUS5"
						(effects
							(font
								(size 1.27 1.27)
							)
						)
					)
					(number "42"
						(effects
							(font
								(size 1.27 1.27)
							)
						)
					)
				)
				(pin bidirectional line
					(at 31.75 -58.42 180)
					(length 2.54)
					(name "CDBUS6"
						(effects
							(font
								(size 1.27 1.27)
							)
						)
					)
					(number "43"
						(effects
							(font
								(size 1.27 1.27)
							)
						)
					)
				)
				(pin bidirectional line
					(at 31.75 -60.96 180)
					(length 2.54)
					(name "CDBUS7"
						(effects
							(font
								(size 1.27 1.27)
							)
						)
					)
					(number "44"
						(effects
							(font
								(size 1.27 1.27)
							)
						)
					)
				)
				(pin bidirectional line
					(at 31.75 -64.77 180)
					(length 2.54)
					(name "DDBUS0"
						(effects
							(font
								(size 1.27 1.27)
							)
						)
					)
					(number "48"
						(effects
							(font
								(size 1.27 1.27)
							)
						)
					)
				)
				(pin bidirectional line
					(at 31.75 -67.31 180)
					(length 2.54)
					(name "DDBUS1"
						(effects
							(font
								(size 1.27 1.27)
							)
						)
					)
					(number "49"
						(effects
							(font
								(size 1.27 1.27)
							)
						)
					)
				)
				(pin bidirectional line
					(at 31.75 -69.85 180)
					(length 2.54)
					(name "DDBUS2"
						(effects
							(font
								(size 1.27 1.27)
							)
						)
					)
					(number "50"
						(effects
							(font
								(size 1.27 1.27)
							)
						)
					)
				)
				(pin bidirectional line
					(at 31.75 -72.39 180)
					(length 2.54)
					(name "DDBUS3"
						(effects
							(font
								(size 1.27 1.27)
							)
						)
					)
					(number "51"
						(effects
							(font
								(size 1.27 1.27)
							)
						)
					)
				)
				(pin bidirectional line
					(at 31.75 -74.93 180)
					(length 2.54)
					(name "DDBUS4"
						(effects
							(font
								(size 1.27 1.27)
							)
						)
					)
					(number "52"
						(effects
							(font
								(size 1.27 1.27)
							)
						)
					)
				)
				(pin bidirectional line
					(at 31.75 -77.47 180)
					(length 2.54)
					(name "DDBUS5"
						(effects
							(font
								(size 1.27 1.27)
							)
						)
					)
					(number "53"
						(effects
							(font
								(size 1.27 1.27)
							)
						)
					)
				)
				(pin bidirectional line
					(at 31.75 -80.01 180)
					(length 2.54)
					(name "DDBUS6"
						(effects
							(font
								(size 1.27 1.27)
							)
						)
					)
					(number "56"
						(effects
							(font
								(size 1.27 1.27)
							)
						)
					)
				)
				(pin bidirectional line
					(at 31.75 -82.55 180)
					(length 2.54)
					(name "DDBUS7"
						(effects
							(font
								(size 1.27 1.27)
							)
						)
					)
					(number "57"
						(effects
							(font
								(size 1.27 1.27)
							)
						)
					)
				)
				(pin bidirectional line
					(at 31.75 -86.36 180)
					(length 2.54)
					(name "GPIO0"
						(effects
							(font
								(size 1.27 1.27)
							)
						)
					)
					(number "61"
						(effects
							(font
								(size 1.27 1.27)
							)
						)
					)
				)
				(pin bidirectional line
					(at 31.75 -88.9 180)
					(length 2.54)
					(name "GPIO1"
						(effects
							(font
								(size 1.27 1.27)
							)
						)
					)
					(number "60"
						(effects
							(font
								(size 1.27 1.27)
							)
						)
					)
				)
				(pin bidirectional line
					(at 31.75 -91.44 180)
					(length 2.54)
					(name "GPIO2"
						(effects
							(font
								(size 1.27 1.27)
							)
						)
					)
					(number "59"
						(effects
							(font
								(size 1.27 1.27)
							)
						)
					)
				)
				(pin bidirectional line
					(at 31.75 -93.98 180)
					(length 2.54)
					(name "GPIO3"
						(effects
							(font
								(size 1.27 1.27)
							)
						)
					)
					(number "5"
						(effects
							(font
								(size 1.27 1.27)
							)
						)
					)
				)
				(pin bidirectional line
					(at 31.75 -96.52 180)
					(length 2.54)
					(name "GPIO4"
						(effects
							(font
								(size 1.27 1.27)
							)
						)
					)
					(number "6"
						(effects
							(font
								(size 1.27 1.27)
							)
						)
					)
				)
				(pin bidirectional line
					(at 31.75 -99.06 180)
					(length 2.54)
					(name "GPIO5"
						(effects
							(font
								(size 1.27 1.27)
							)
						)
					)
					(number "7"
						(effects
							(font
								(size 1.27 1.27)
							)
						)
					)
				)
				(pin bidirectional line
					(at 31.75 -101.6 180)
					(length 2.54)
					(name "GPIO6"
						(effects
							(font
								(size 1.27 1.27)
							)
						)
					)
					(number "46"
						(effects
							(font
								(size 1.27 1.27)
							)
						)
					)
				)
				(pin bidirectional line
					(at 31.75 -104.14 180)
					(length 2.54)
					(name "GPIO7"
						(effects
							(font
								(size 1.27 1.27)
							)
						)
					)
					(number "58"
						(effects
							(font
								(size 1.27 1.27)
							)
						)
					)
				)
			)
		)
	(symbol "antmicroInterfaceControllers:TUSB321RWBR"
			(exclude_from_sim no)
			(in_bom yes)
			(on_board yes)
			(property "Reference" "U"
				(at 45.72 -2.54 0)
				(effects
					(font
						(size 1.27 1.27)
						(thickness 0.15)
					)
					(justify left bottom)
				)
			)
			(property "Value" "TUSB321RWBR"
				(at 45.72 -5.08 0)
				(effects
					(font
						(size 1.27 1.27)
						(thickness 0.15)
					)
					(justify left bottom)
					(hide yes)
				)
			)
			(property "Footprint" "antmicro-footprints:Texas_X2QFN-12_1.6x1.6mm_P0.4mm"
				(at 45.72 -7.62 0)
				(effects
					(font
						(size 1.27 1.27)
						(thickness 0.15)
					)
					(justify left bottom)
					(hide yes)
				)
			)
			(property "Datasheet" "https://www.ti.com/lit/ds/symlink/tusb321.pdf?ts=1709901243739"
				(at 45.72 -10.16 0)
				(effects
					(font
						(size 1.27 1.27)
						(thickness 0.15)
					)
					(justify left bottom)
					(hide yes)
				)
			)
			(property "Description" "USB Interface 12-X2QFN (1.6x1.6)"
				(at 0 0 0)
				(effects
					(font
						(size 1.27 1.27)
					)
					(hide yes)
				)
			)
			(property "MPN" "TUSB321RWBR"
				(at 45.72 -12.7 0)
				(effects
					(font
						(size 1.27 1.27)
						(thickness 0.15)
					)
					(justify left bottom)
				)
			)
			(property "Manufacturer" "Texas Instruments"
				(at 45.72 -15.24 0)
				(effects
					(font
						(size 1.27 1.27)
						(thickness 0.15)
					)
					(justify left bottom)
					(hide yes)
				)
			)
			(property "Author" "Antmicro"
				(at 45.72 -17.78 0)
				(effects
					(font
						(size 1.27 1.27)
						(thickness 0.15)
					)
					(justify left bottom)
					(hide yes)
				)
			)
			(property "License" "Apache-2.0"
				(at 45.72 -20.32 0)
				(effects
					(font
						(size 1.27 1.27)
						(thickness 0.15)
					)
					(justify left bottom)
					(hide yes)
				)
			)
			(property "ki_keywords" "IC"
				(at 0 0 0)
				(effects
					(font
						(size 1.27 1.27)
					)
					(hide yes)
				)
			)
			(symbol "TUSB321RWBR_1_1"
				(rectangle
					(start 2.54 2.54)
					(end 27.94 -17.78)
					(stroke
						(width 0.254)
						(type default)
					)
					(fill
						(type background)
					)
				)
				(pin power_in line
					(at 0 0 0)
					(length 2.54)
					(name "VDD"
						(effects
							(font
								(size 1.27 1.27)
							)
						)
					)
					(number "12"
						(effects
							(font
								(size 1.27 1.27)
							)
						)
					)
				)
				(pin bidirectional line
					(at 0 -3.81 0)
					(length 2.54)
					(name "CC1"
						(effects
							(font
								(size 1.27 1.27)
							)
						)
					)
					(number "1"
						(effects
							(font
								(size 1.27 1.27)
							)
						)
					)
				)
				(pin bidirectional line
					(at 0 -6.35 0)
					(length 2.54)
					(name "CC2"
						(effects
							(font
								(size 1.27 1.27)
							)
						)
					)
					(number "2"
						(effects
							(font
								(size 1.27 1.27)
							)
						)
					)
				)
				(pin input line
					(at 0 -10.16 0)
					(length 2.54)
					(name "VBUS_DET"
						(effects
							(font
								(size 1.27 1.27)
							)
						)
					)
					(number "5"
						(effects
							(font
								(size 1.27 1.27)
							)
						)
					)
				)
				(pin power_in line
					(at 0 -15.24 0)
					(length 2.54)
					(name "GND"
						(effects
							(font
								(size 1.27 1.27)
							)
						)
					)
					(number "10"
						(effects
							(font
								(size 1.27 1.27)
							)
						)
					)
				)
				(pin open_collector line
					(at 30.48 0 180)
					(length 2.54)
					(name "DIR"
						(effects
							(font
								(size 1.27 1.27)
							)
						)
					)
					(number "11"
						(effects
							(font
								(size 1.27 1.27)
							)
						)
					)
				)
				(pin input line
					(at 30.48 -2.54 180)
					(length 2.54)
					(name "CURRENT_MODE"
						(effects
							(font
								(size 1.27 1.27)
							)
						)
					)
					(number "3"
						(effects
							(font
								(size 1.27 1.27)
							)
						)
					)
				)
				(pin input line
					(at 30.48 -5.08 180)
					(length 2.54)
					(name "PORT"
						(effects
							(font
								(size 1.27 1.27)
							)
						)
					)
					(number "4"
						(effects
							(font
								(size 1.27 1.27)
							)
						)
					)
				)
				(pin open_collector line
					(at 30.48 -7.62 180)
					(length 2.54)
					(name "ID"
						(effects
							(font
								(size 1.27 1.27)
							)
						)
					)
					(number "9"
						(effects
							(font
								(size 1.27 1.27)
							)
						)
					)
				)
				(pin open_collector line
					(at 30.48 -10.16 180)
					(length 2.54)
					(name "~{VCONN_FAULT}"
						(effects
							(font
								(size 1.27 1.27)
							)
						)
					)
					(number "6"
						(effects
							(font
								(size 1.27 1.27)
							)
						)
					)
				)
				(pin open_collector line
					(at 30.48 -12.7 180)
					(length 2.54)
					(name "OUT1"
						(effects
							(font
								(size 1.27 1.27)
							)
						)
					)
					(number "7"
						(effects
							(font
								(size 1.27 1.27)
							)
						)
					)
				)
				(pin open_collector line
					(at 30.48 -15.24 180)
					(length 2.54)
					(name "OUT2"
						(effects
							(font
								(size 1.27 1.27)
							)
						)
					)
					(number "8"
						(effects
							(font
								(size 1.27 1.27)
							)
						)
					)
				)
			)
		)
	(symbol "antmicroInterfaceIOExpanders:MCP23017T-E_QFN"
			(exclude_from_sim no)
			(in_bom yes)
			(on_board yes)
			(property "Reference" "U"
				(at 38.1 -6.35 0)
				(effects
					(font
						(size 1.27 1.27)
						(thickness 0.15)
					)
					(justify left bottom)
				)
			)
			(property "Value" "MCP23017T-E_QFN"
				(at 38.1 -11.43 0)
				(effects
					(font
						(size 1.27 1.27)
						(thickness 0.15)
					)
					(justify left bottom)
					(hide yes)
				)
			)
			(property "Footprint" "antmicro-footprints:QFN-28-1EP_6x6mm_P0.65mm_EP3.7x3.7mm"
				(at 38.1 -13.97 0)
				(effects
					(font
						(size 1.27 1.27)
						(thickness 0.15)
					)
					(justify left bottom)
					(hide yes)
				)
			)
			(property "Datasheet" "https://ww1.microchip.com/downloads/aemDocuments/documents/APID/ProductDocuments/DataSheets/MCP23017-Data-Sheet-DS20001952.pdf"
				(at 38.1 -16.51 0)
				(effects
					(font
						(size 1.27 1.27)
						(thickness 0.15)
					)
					(justify left bottom)
					(hide yes)
				)
			)
			(property "Description" "I/O Expander, 16 bit, I2C, 1.8-5.5 V, QFN, 28 Pins"
				(at 0 0 0)
				(effects
					(font
						(size 1.27 1.27)
					)
					(hide yes)
				)
			)
			(property "Manufacturer" "Microchip Technology"
				(at 38.1 -19.05 0)
				(effects
					(font
						(size 1.27 1.27)
						(thickness 0.15)
					)
					(justify left bottom)
					(hide yes)
				)
			)
			(property "MPN" "MCP23017T-E/ML"
				(at 38.1 -8.89 0)
				(effects
					(font
						(size 1.27 1.27)
						(thickness 0.15)
					)
					(justify left bottom)
				)
			)
			(property "Author" "Antmicro"
				(at 38.1 -21.59 0)
				(effects
					(font
						(size 1.27 1.27)
						(thickness 0.15)
					)
					(justify left bottom)
					(hide yes)
				)
			)
			(property "License" "Apache-2.0"
				(at 38.1 -24.13 0)
				(effects
					(font
						(size 1.27 1.27)
						(thickness 0.15)
					)
					(justify left bottom)
					(hide yes)
				)
			)
			(property "ki_keywords" "IC, SMT"
				(at 0 0 0)
				(effects
					(font
						(size 1.27 1.27)
					)
					(hide yes)
				)
			)
			(symbol "MCP23017T-E_QFN_1_1"
				(rectangle
					(start 2.54 2.54)
					(end 22.86 -43.18)
					(stroke
						(width 0.254)
						(type default)
					)
					(fill
						(type background)
					)
				)
				(pin power_in line
					(at 0 0 0)
					(length 2.54)
					(name "VDD"
						(effects
							(font
								(size 1.27 1.27)
							)
						)
					)
					(number "5"
						(effects
							(font
								(size 1.27 1.27)
							)
						)
					)
				)
				(pin bidirectional line
					(at 0 -5.08 0)
					(length 2.54)
					(name "SDA"
						(effects
							(font
								(size 1.27 1.27)
							)
						)
					)
					(number "9"
						(effects
							(font
								(size 1.27 1.27)
							)
						)
					)
				)
				(pin input line
					(at 0 -7.62 0)
					(length 2.54)
					(name "SCK"
						(effects
							(font
								(size 1.27 1.27)
							)
						)
					)
					(number "8"
						(effects
							(font
								(size 1.27 1.27)
							)
						)
					)
				)
				(pin input line
					(at 0 -12.7 0)
					(length 2.54)
					(name "~{RESET}"
						(effects
							(font
								(size 1.27 1.27)
							)
						)
					)
					(number "14"
						(effects
							(font
								(size 1.27 1.27)
							)
						)
					)
				)
				(pin output line
					(at 0 -15.24 0)
					(length 2.54)
					(name "INTA"
						(effects
							(font
								(size 1.27 1.27)
							)
						)
					)
					(number "16"
						(effects
							(font
								(size 1.27 1.27)
							)
						)
					)
				)
				(pin output line
					(at 0 -17.78 0)
					(length 2.54)
					(name "INTB"
						(effects
							(font
								(size 1.27 1.27)
							)
						)
					)
					(number "15"
						(effects
							(font
								(size 1.27 1.27)
							)
						)
					)
				)
				(pin input line
					(at 0 -27.94 0)
					(length 2.54)
					(name "A0"
						(effects
							(font
								(size 1.27 1.27)
							)
						)
					)
					(number "11"
						(effects
							(font
								(size 1.27 1.27)
							)
						)
					)
				)
				(pin input line
					(at 0 -30.48 0)
					(length 2.54)
					(name "A1"
						(effects
							(font
								(size 1.27 1.27)
							)
						)
					)
					(number "12"
						(effects
							(font
								(size 1.27 1.27)
							)
						)
					)
				)
				(pin input line
					(at 0 -33.02 0)
					(length 2.54)
					(name "A2"
						(effects
							(font
								(size 1.27 1.27)
							)
						)
					)
					(number "13"
						(effects
							(font
								(size 1.27 1.27)
							)
						)
					)
				)
				(pin power_in line
					(at 0 -38.1 0)
					(length 2.54)
					(name "VSS"
						(effects
							(font
								(size 1.27 1.27)
							)
						)
					)
					(number "6"
						(effects
							(font
								(size 1.27 1.27)
							)
						)
					)
				)
				(pin power_in line
					(at 0 -40.64 0)
					(length 2.54)
					(name "EP"
						(effects
							(font
								(size 1.27 1.27)
							)
						)
					)
					(number "29"
						(effects
							(font
								(size 1.27 1.27)
							)
						)
					)
				)
				(pin no_connect line
					(at 2.54 -21.59 0)
					(length 2.54)
					(hide yes)
					(name "NC"
						(effects
							(font
								(size 1.27 1.27)
							)
						)
					)
					(number "7"
						(effects
							(font
								(size 1.27 1.27)
							)
						)
					)
				)
				(pin no_connect line
					(at 2.54 -24.13 0)
					(length 2.54)
					(hide yes)
					(name "NC"
						(effects
							(font
								(size 1.27 1.27)
							)
						)
					)
					(number "10"
						(effects
							(font
								(size 1.27 1.27)
							)
						)
					)
				)
				(pin bidirectional line
					(at 25.4 0 180)
					(length 2.54)
					(name "GPA0"
						(effects
							(font
								(size 1.27 1.27)
							)
						)
					)
					(number "17"
						(effects
							(font
								(size 1.27 1.27)
							)
						)
					)
				)
				(pin bidirectional line
					(at 25.4 -2.54 180)
					(length 2.54)
					(name "GPA1"
						(effects
							(font
								(size 1.27 1.27)
							)
						)
					)
					(number "18"
						(effects
							(font
								(size 1.27 1.27)
							)
						)
					)
				)
				(pin bidirectional line
					(at 25.4 -5.08 180)
					(length 2.54)
					(name "GPA2"
						(effects
							(font
								(size 1.27 1.27)
							)
						)
					)
					(number "19"
						(effects
							(font
								(size 1.27 1.27)
							)
						)
					)
				)
				(pin bidirectional line
					(at 25.4 -7.62 180)
					(length 2.54)
					(name "GPA3"
						(effects
							(font
								(size 1.27 1.27)
							)
						)
					)
					(number "20"
						(effects
							(font
								(size 1.27 1.27)
							)
						)
					)
				)
				(pin bidirectional line
					(at 25.4 -10.16 180)
					(length 2.54)
					(name "GPA4"
						(effects
							(font
								(size 1.27 1.27)
							)
						)
					)
					(number "21"
						(effects
							(font
								(size 1.27 1.27)
							)
						)
					)
				)
				(pin bidirectional line
					(at 25.4 -12.7 180)
					(length 2.54)
					(name "GPA5"
						(effects
							(font
								(size 1.27 1.27)
							)
						)
					)
					(number "22"
						(effects
							(font
								(size 1.27 1.27)
							)
						)
					)
				)
				(pin bidirectional line
					(at 25.4 -15.24 180)
					(length 2.54)
					(name "GPA6"
						(effects
							(font
								(size 1.27 1.27)
							)
						)
					)
					(number "23"
						(effects
							(font
								(size 1.27 1.27)
							)
						)
					)
				)
				(pin output line
					(at 25.4 -17.78 180)
					(length 2.54)
					(name "GPA7"
						(effects
							(font
								(size 1.27 1.27)
							)
						)
					)
					(number "24"
						(effects
							(font
								(size 1.27 1.27)
							)
						)
					)
				)
				(pin bidirectional line
					(at 25.4 -22.86 180)
					(length 2.54)
					(name "GPB0"
						(effects
							(font
								(size 1.27 1.27)
							)
						)
					)
					(number "25"
						(effects
							(font
								(size 1.27 1.27)
							)
						)
					)
				)
				(pin bidirectional line
					(at 25.4 -25.4 180)
					(length 2.54)
					(name "GPB1"
						(effects
							(font
								(size 1.27 1.27)
							)
						)
					)
					(number "26"
						(effects
							(font
								(size 1.27 1.27)
							)
						)
					)
				)
				(pin bidirectional line
					(at 25.4 -27.94 180)
					(length 2.54)
					(name "GPB2"
						(effects
							(font
								(size 1.27 1.27)
							)
						)
					)
					(number "27"
						(effects
							(font
								(size 1.27 1.27)
							)
						)
					)
				)
				(pin bidirectional line
					(at 25.4 -30.48 180)
					(length 2.54)
					(name "GPB3"
						(effects
							(font
								(size 1.27 1.27)
							)
						)
					)
					(number "28"
						(effects
							(font
								(size 1.27 1.27)
							)
						)
					)
				)
				(pin bidirectional line
					(at 25.4 -33.02 180)
					(length 2.54)
					(name "GPB4"
						(effects
							(font
								(size 1.27 1.27)
							)
						)
					)
					(number "1"
						(effects
							(font
								(size 1.27 1.27)
							)
						)
					)
				)
				(pin bidirectional line
					(at 25.4 -35.56 180)
					(length 2.54)
					(name "GPB5"
						(effects
							(font
								(size 1.27 1.27)
							)
						)
					)
					(number "2"
						(effects
							(font
								(size 1.27 1.27)
							)
						)
					)
				)
				(pin bidirectional line
					(at 25.4 -38.1 180)
					(length 2.54)
					(name "GPB6"
						(effects
							(font
								(size 1.27 1.27)
							)
						)
					)
					(number "3"
						(effects
							(font
								(size 1.27 1.27)
							)
						)
					)
				)
				(pin output line
					(at 25.4 -40.64 180)
					(length 2.54)
					(name "GPB7"
						(effects
							(font
								(size 1.27 1.27)
							)
						)
					)
					(number "4"
						(effects
							(font
								(size 1.27 1.27)
							)
						)
					)
				)
			)
		)
	(symbol "antmicroLEDIndicationDiscrete:LED_G_0603_KP-1608CGCK"
			(pin_numbers
				(hide yes)
			)
			(pin_names
				(hide yes)
			)
			(exclude_from_sim no)
			(in_bom yes)
			(on_board yes)
			(property "Reference" "D"
				(at 22.86 -2.54 0)
				(effects
					(font
						(size 1.27 1.27)
						(thickness 0.15)
					)
					(justify left bottom)
				)
			)
			(property "Value" "LED_G_0603_KP-1608CGCK"
				(at 22.86 -7.62 0)
				(effects
					(font
						(size 1.27 1.27)
						(thickness 0.15)
					)
					(justify left bottom)
					(hide yes)
				)
			)
			(property "Footprint" "antmicro-footprints:LED_0603_1608Metric_G"
				(at 22.86 -10.16 0)
				(effects
					(font
						(size 1.27 1.27)
						(thickness 0.15)
					)
					(justify left bottom)
					(hide yes)
				)
			)
			(property "Datasheet" "http://www.kingbright.com/attachments/file/psearch//000/00/00/KP-1608CGCK(Ver.23B).pdf"
				(at 22.86 -12.7 0)
				(effects
					(font
						(size 1.27 1.27)
						(thickness 0.15)
					)
					(justify left bottom)
					(hide yes)
				)
			)
			(property "Description" "LED, Green, SMD, 0603, 20 mA, 2.1 V, 570 nm"
				(at 0 0 0)
				(effects
					(font
						(size 1.27 1.27)
					)
					(hide yes)
				)
			)
			(property "MPN" "KP-1608CGCK"
				(at 22.86 -15.24 0)
				(effects
					(font
						(size 1.27 1.27)
						(thickness 0.15)
					)
					(justify left bottom)
					(hide yes)
				)
			)
			(property "Manufacturer" "Kingbright"
				(at 22.86 -17.78 0)
				(effects
					(font
						(size 1.27 1.27)
						(thickness 0.15)
					)
					(justify left bottom)
					(hide yes)
				)
			)
			(property "Color" "Green"
				(at 22.86 -5.08 0)
				(effects
					(font
						(size 1.27 1.27)
					)
					(justify left bottom)
				)
			)
			(property "Author" "Antmicro"
				(at 22.86 -20.32 0)
				(effects
					(font
						(size 1.27 1.27)
						(thickness 0.15)
					)
					(justify left bottom)
					(hide yes)
				)
			)
			(property "License" "Apache-2.0"
				(at 22.86 -22.86 0)
				(effects
					(font
						(size 1.27 1.27)
						(thickness 0.15)
					)
					(justify left bottom)
					(hide yes)
				)
			)
			(property "ki_keywords" "SMT, DIODE, SEMICONDUCTOR, LED"
				(at 0 0 0)
				(effects
					(font
						(size 1.27 1.27)
					)
					(hide yes)
				)
			)
			(symbol "LED_G_0603_KP-1608CGCK_0_1"
				(polyline
					(pts
						(xy 1.905 0) (xy 0.635 0)
					)
					(stroke
						(width 0)
						(type default)
					)
					(fill
						(type none)
					)
				)
				(polyline
					(pts
						(xy 4.445 0) (xy 3.175 0)
					)
					(stroke
						(width 0)
						(type default)
					)
					(fill
						(type none)
					)
				)
			)
			(symbol "LED_G_0603_KP-1608CGCK_1_1"
				(polyline
					(pts
						(xy 1.143 2.286) (xy 1.143 1.778) (xy 1.143 2.286) (xy 1.651 2.286) (xy 1.143 2.286) (xy 2.159 1.27)
					)
					(stroke
						(width 0.254)
						(type default)
					)
					(fill
						(type none)
					)
				)
				(polyline
					(pts
						(xy 1.778 1.016) (xy 1.778 -1.016)
					)
					(stroke
						(width 0.254)
						(type default)
					)
					(fill
						(type none)
					)
				)
				(polyline
					(pts
						(xy 2.159 2.54) (xy 2.159 2.032) (xy 2.159 2.54) (xy 2.667 2.54) (xy 2.159 2.54) (xy 3.048 1.651)
					)
					(stroke
						(width 0.254)
						(type default)
					)
					(fill
						(type none)
					)
				)
				(polyline
					(pts
						(xy 3.302 1.016) (xy 3.302 -1.016) (xy 1.778 0) (xy 3.302 1.016)
					)
					(stroke
						(width 0.254)
						(type default)
					)
					(fill
						(type outline)
					)
				)
				(pin passive line
					(at 0 0 0)
					(length 0.635)
					(name "C"
						(effects
							(font
								(size 1.27 1.27)
							)
						)
					)
					(number "1"
						(effects
							(font
								(size 1.27 1.27)
							)
						)
					)
				)
				(pin passive line
					(at 5.08 0 180)
					(length 0.635)
					(name "A"
						(effects
							(font
								(size 1.27 1.27)
							)
						)
					)
					(number "2"
						(effects
							(font
								(size 1.27 1.27)
							)
						)
					)
				)
			)
		)
	(symbol "antmicroLEDIndicationDiscrete:LED_Y_0402_VLMY1500-GS08"
			(pin_numbers
				(hide yes)
			)
			(pin_names
				(hide yes)
			)
			(exclude_from_sim no)
			(in_bom yes)
			(on_board yes)
			(property "Reference" "D"
				(at 22.86 -2.54 0)
				(effects
					(font
						(size 1.27 1.27)
						(thickness 0.15)
					)
					(justify left bottom)
				)
			)
			(property "Value" "LED_Y_0402_VLMY1500-GS08"
				(at 22.86 -7.62 0)
				(effects
					(font
						(size 1.27 1.27)
						(thickness 0.15)
					)
					(justify left bottom)
					(hide yes)
				)
			)
			(property "Footprint" "antmicro-footprints:LED_0402_1005Metric_Y"
				(at 22.86 -10.16 0)
				(effects
					(font
						(size 1.27 1.27)
						(thickness 0.15)
					)
					(justify left bottom)
					(hide yes)
				)
			)
			(property "Datasheet" "https://www.vishay.com/docs/82554/vlmo1500.pdf"
				(at 22.86 -12.7 0)
				(effects
					(font
						(size 1.27 1.27)
						(thickness 0.15)
					)
					(justify left bottom)
					(hide yes)
				)
			)
			(property "Description" "LED, Yellow, SMD, 0402, 30 mA, 2 V, 590 nm"
				(at 0 0 0)
				(effects
					(font
						(size 1.27 1.27)
					)
					(hide yes)
				)
			)
			(property "MPN" "VLMY1500-GS08"
				(at 22.86 -15.24 0)
				(effects
					(font
						(size 1.27 1.27)
						(thickness 0.15)
					)
					(justify left bottom)
					(hide yes)
				)
			)
			(property "Manufacturer" "Vishay"
				(at 22.86 -17.78 0)
				(effects
					(font
						(size 1.27 1.27)
						(thickness 0.15)
					)
					(justify left bottom)
					(hide yes)
				)
			)
			(property "Color" "Yellow"
				(at 22.86 -5.08 0)
				(effects
					(font
						(size 1.27 1.27)
					)
					(justify left bottom)
				)
			)
			(property "Author" "Antmicro"
				(at 22.86 -20.32 0)
				(effects
					(font
						(size 1.27 1.27)
						(thickness 0.15)
					)
					(justify left bottom)
					(hide yes)
				)
			)
			(property "License" "Apache-2.0"
				(at 22.86 -22.86 0)
				(effects
					(font
						(size 1.27 1.27)
						(thickness 0.15)
					)
					(justify left bottom)
					(hide yes)
				)
			)
			(property "ki_keywords" "SMT, DIODE, SEMICONDUCTOR, LED"
				(at 0 0 0)
				(effects
					(font
						(size 1.27 1.27)
					)
					(hide yes)
				)
			)
			(symbol "LED_Y_0402_VLMY1500-GS08_0_1"
				(polyline
					(pts
						(xy 1.905 0) (xy 0.635 0)
					)
					(stroke
						(width 0)
						(type default)
					)
					(fill
						(type none)
					)
				)
				(polyline
					(pts
						(xy 4.445 0) (xy 3.175 0)
					)
					(stroke
						(width 0)
						(type default)
					)
					(fill
						(type none)
					)
				)
			)
			(symbol "LED_Y_0402_VLMY1500-GS08_1_1"
				(polyline
					(pts
						(xy 1.143 2.286) (xy 1.143 1.778) (xy 1.143 2.286) (xy 1.651 2.286) (xy 1.143 2.286) (xy 2.159 1.27)
					)
					(stroke
						(width 0.254)
						(type default)
					)
					(fill
						(type none)
					)
				)
				(polyline
					(pts
						(xy 1.778 1.016) (xy 1.778 -1.016)
					)
					(stroke
						(width 0.254)
						(type default)
					)
					(fill
						(type none)
					)
				)
				(polyline
					(pts
						(xy 2.159 2.54) (xy 2.159 2.032) (xy 2.159 2.54) (xy 2.667 2.54) (xy 2.159 2.54) (xy 3.048 1.651)
					)
					(stroke
						(width 0.254)
						(type default)
					)
					(fill
						(type none)
					)
				)
				(polyline
					(pts
						(xy 3.302 1.016) (xy 3.302 -1.016) (xy 1.778 0) (xy 3.302 1.016)
					)
					(stroke
						(width 0.254)
						(type default)
					)
					(fill
						(type outline)
					)
				)
				(pin passive line
					(at 0 0 0)
					(length 0.635)
					(name "C"
						(effects
							(font
								(size 1.27 1.27)
							)
						)
					)
					(number "1"
						(effects
							(font
								(size 1.27 1.27)
							)
						)
					)
				)
				(pin passive line
					(at 5.08 0 180)
					(length 0.635)
					(name "A"
						(effects
							(font
								(size 1.27 1.27)
							)
						)
					)
					(number "2"
						(effects
							(font
								(size 1.27 1.27)
							)
						)
					)
				)
			)
		)
	(symbol "antmicroLogicTranslatorsLevelShifters:NTS0104_DHVQFN"
			(exclude_from_sim no)
			(in_bom yes)
			(on_board yes)
			(property "Reference" "U"
				(at 35.56 -2.54 0)
				(effects
					(font
						(size 1.27 1.27)
						(thickness 0.15)
					)
					(justify left bottom)
				)
			)
			(property "Value" "NTS0104_DHVQFN"
				(at 35.56 -7.62 0)
				(effects
					(font
						(size 1.27 1.27)
						(thickness 0.15)
					)
					(justify left bottom)
					(hide yes)
				)
			)
			(property "Footprint" "antmicro-footprints:DHVQFN-14-1EP_2.5x3mm"
				(at 35.56 -10.16 0)
				(effects
					(font
						(size 1.27 1.27)
						(thickness 0.15)
					)
					(justify left bottom)
					(hide yes)
				)
			)
			(property "Datasheet" "https://www.nxp.com/docs/en/data-sheet/NTS0104.pdf"
				(at 35.56 -12.7 0)
				(effects
					(font
						(size 1.27 1.27)
						(thickness 0.15)
					)
					(justify left bottom)
					(hide yes)
				)
			)
			(property "Description" "Voltage Level Translator Bidirectional 1 Circuit 4 Channel 50Mbps 14-DHVQFN (2.5x3)"
				(at 0 0 0)
				(effects
					(font
						(size 1.27 1.27)
					)
					(hide yes)
				)
			)
			(property "MPN" "NTS0104BQ"
				(at 35.56 -5.08 0)
				(effects
					(font
						(size 1.27 1.27)
						(thickness 0.15)
					)
					(justify left bottom)
				)
			)
			(property "Manufacturer" "NXP"
				(at 35.56 -15.24 0)
				(effects
					(font
						(size 1.27 1.27)
						(thickness 0.15)
					)
					(justify left bottom)
					(hide yes)
				)
			)
			(property "Author" "Antmicro"
				(at 35.56 -17.78 0)
				(effects
					(font
						(size 1.27 1.27)
						(thickness 0.15)
					)
					(justify left bottom)
					(hide yes)
				)
			)
			(property "License" "Apache-2.0"
				(at 35.56 -20.32 0)
				(effects
					(font
						(size 1.27 1.27)
						(thickness 0.15)
					)
					(justify left bottom)
					(hide yes)
				)
			)
			(property "ki_keywords" "IC, LEVEL-SHIFTER"
				(at 0 0 0)
				(effects
					(font
						(size 1.27 1.27)
					)
					(hide yes)
				)
			)
			(symbol "NTS0104_DHVQFN_1_1"
				(rectangle
					(start 2.54 2.54)
					(end 17.78 -17.78)
					(stroke
						(width 0.254)
						(type default)
					)
					(fill
						(type background)
					)
				)
				(pin power_in line
					(at 0 0 0)
					(length 2.54)
					(name "VCC_A"
						(effects
							(font
								(size 1.27 1.27)
							)
						)
					)
					(number "1"
						(effects
							(font
								(size 1.27 1.27)
							)
						)
					)
				)
				(pin passive line
					(at 0 -2.54 0)
					(length 2.54)
					(name "OE"
						(effects
							(font
								(size 1.27 1.27)
							)
						)
					)
					(number "8"
						(effects
							(font
								(size 1.27 1.27)
							)
						)
					)
				)
				(pin passive line
					(at 0 -5.08 0)
					(length 2.54)
					(name "A1"
						(effects
							(font
								(size 1.27 1.27)
							)
						)
					)
					(number "2"
						(effects
							(font
								(size 1.27 1.27)
							)
						)
					)
				)
				(pin passive line
					(at 0 -7.62 0)
					(length 2.54)
					(name "A2"
						(effects
							(font
								(size 1.27 1.27)
							)
						)
					)
					(number "3"
						(effects
							(font
								(size 1.27 1.27)
							)
						)
					)
				)
				(pin passive line
					(at 0 -10.16 0)
					(length 2.54)
					(name "A3"
						(effects
							(font
								(size 1.27 1.27)
							)
						)
					)
					(number "4"
						(effects
							(font
								(size 1.27 1.27)
							)
						)
					)
				)
				(pin passive line
					(at 0 -12.7 0)
					(length 2.54)
					(name "A4"
						(effects
							(font
								(size 1.27 1.27)
							)
						)
					)
					(number "5"
						(effects
							(font
								(size 1.27 1.27)
							)
						)
					)
				)
				(pin power_in line
					(at 0 -15.24 0)
					(length 2.54)
					(name "GNDPAD"
						(effects
							(font
								(size 1.27 1.27)
							)
						)
					)
					(number "15"
						(effects
							(font
								(size 1.27 1.27)
							)
						)
					)
				)
				(pin no_connect line
					(at 17.78 -2.54 180)
					(length 2.54)
					(hide yes)
					(name "NC"
						(effects
							(font
								(size 1.27 1.27)
							)
						)
					)
					(number "6"
						(effects
							(font
								(size 1.27 1.27)
							)
						)
					)
				)
				(pin no_connect line
					(at 17.78 -3.81 180)
					(length 2.54)
					(hide yes)
					(name "NC"
						(effects
							(font
								(size 1.27 1.27)
							)
						)
					)
					(number "9"
						(effects
							(font
								(size 1.27 1.27)
							)
						)
					)
				)
				(pin power_in line
					(at 20.32 0 180)
					(length 2.54)
					(name "VCC_B"
						(effects
							(font
								(size 1.27 1.27)
							)
						)
					)
					(number "14"
						(effects
							(font
								(size 1.27 1.27)
							)
						)
					)
				)
				(pin passive line
					(at 20.32 -5.08 180)
					(length 2.54)
					(name "B1"
						(effects
							(font
								(size 1.27 1.27)
							)
						)
					)
					(number "13"
						(effects
							(font
								(size 1.27 1.27)
							)
						)
					)
				)
				(pin passive line
					(at 20.32 -7.62 180)
					(length 2.54)
					(name "B2"
						(effects
							(font
								(size 1.27 1.27)
							)
						)
					)
					(number "12"
						(effects
							(font
								(size 1.27 1.27)
							)
						)
					)
				)
				(pin passive line
					(at 20.32 -10.16 180)
					(length 2.54)
					(name "B3"
						(effects
							(font
								(size 1.27 1.27)
							)
						)
					)
					(number "11"
						(effects
							(font
								(size 1.27 1.27)
							)
						)
					)
				)
				(pin passive line
					(at 20.32 -12.7 180)
					(length 2.54)
					(name "B4"
						(effects
							(font
								(size 1.27 1.27)
							)
						)
					)
					(number "10"
						(effects
							(font
								(size 1.27 1.27)
							)
						)
					)
				)
				(pin power_in line
					(at 20.32 -15.24 180)
					(length 2.54)
					(name "GND"
						(effects
							(font
								(size 1.27 1.27)
							)
						)
					)
					(number "7"
						(effects
							(font
								(size 1.27 1.27)
							)
						)
					)
				)
			)
		)
	(symbol "antmicroLogicTranslatorsLevelShifters:TXB0104_UQFN"
			(exclude_from_sim no)
			(in_bom yes)
			(on_board yes)
			(property "Reference" "U"
				(at 35.56 -5.08 0)
				(effects
					(font
						(size 1.27 1.27)
						(thickness 0.15)
					)
					(justify left bottom)
				)
			)
			(property "Value" "TXB0104_UQFN"
				(at 35.56 -7.62 0)
				(effects
					(font
						(size 1.27 1.27)
						(thickness 0.15)
					)
					(justify left bottom)
					(hide yes)
				)
			)
			(property "Footprint" "antmicro-footprints:UQFN-12_2x1.7mm_P0.4mm_Texas_RUT"
				(at 35.56 -10.16 0)
				(effects
					(font
						(size 1.27 1.27)
						(thickness 0.15)
					)
					(justify left bottom)
					(hide yes)
				)
			)
			(property "Datasheet" "http://www.ti.com/lit/ds/symlink/txb0104.pdf"
				(at 35.56 -12.7 0)
				(effects
					(font
						(size 1.27 1.27)
						(thickness 0.15)
					)
					(justify left bottom)
					(hide yes)
				)
			)
			(property "Description" "Level shifter"
				(at 0 0 0)
				(effects
					(font
						(size 1.27 1.27)
					)
					(hide yes)
				)
			)
			(property "Manufacturer" "Texas Instruments"
				(at 35.56 -15.24 0)
				(effects
					(font
						(size 1.27 1.27)
						(thickness 0.15)
					)
					(justify left bottom)
					(hide yes)
				)
			)
			(property "MPN" "TXB0104RUTR"
				(at 35.56 -17.78 0)
				(effects
					(font
						(size 1.27 1.27)
						(thickness 0.15)
					)
					(justify left bottom)
				)
			)
			(property "Author" "Antmicro"
				(at 35.56 -20.32 0)
				(effects
					(font
						(size 1.27 1.27)
						(thickness 0.15)
					)
					(justify left bottom)
					(hide yes)
				)
			)
			(property "License" "Apache-2.0"
				(at 35.56 -22.86 0)
				(effects
					(font
						(size 1.27 1.27)
						(thickness 0.15)
					)
					(justify left bottom)
					(hide yes)
				)
			)
			(property "ki_keywords" "IC"
				(at 0 0 0)
				(effects
					(font
						(size 1.27 1.27)
					)
					(hide yes)
				)
			)
			(property "ki_fp_filters" "Texas*R*PUQFN*N12*"
				(at 0 0 0)
				(effects
					(font
						(size 1.27 1.27)
					)
					(hide yes)
				)
			)
			(symbol "TXB0104_UQFN_1_1"
				(rectangle
					(start 2.54 2.54)
					(end 17.78 -27.94)
					(stroke
						(width 0.254)
						(type default)
					)
					(fill
						(type background)
					)
				)
				(polyline
					(pts
						(xy 7.874 -5.207) (xy 7.874 -4.191) (xy 9.652 -4.191)
					)
					(stroke
						(width 0.254)
						(type default)
					)
					(fill
						(type background)
					)
				)
				(polyline
					(pts
						(xy 7.874 -10.287) (xy 7.874 -9.271) (xy 9.652 -9.271)
					)
					(stroke
						(width 0.254)
						(type default)
					)
					(fill
						(type background)
					)
				)
				(polyline
					(pts
						(xy 7.874 -15.367) (xy 7.874 -14.351) (xy 9.652 -14.351)
					)
					(stroke
						(width 0.254)
						(type default)
					)
					(fill
						(type background)
					)
				)
				(polyline
					(pts
						(xy 7.874 -20.447) (xy 7.874 -19.431) (xy 9.652 -19.431)
					)
					(stroke
						(width 0.254)
						(type default)
					)
					(fill
						(type background)
					)
				)
				(polyline
					(pts
						(xy 9.652 -6.223) (xy 7.874 -6.223) (xy 7.874 -5.207) (xy 5.842 -5.207)
					)
					(stroke
						(width 0.254)
						(type default)
					)
					(fill
						(type background)
					)
				)
				(polyline
					(pts
						(xy 9.652 -6.223) (xy 11.43 -5.207) (xy 11.43 -7.239) (xy 9.652 -6.223)
					)
					(stroke
						(width 0.254)
						(type default)
					)
					(fill
						(type outline)
					)
				)
				(polyline
					(pts
						(xy 9.652 -11.303) (xy 7.874 -11.303) (xy 7.874 -10.287) (xy 6.096 -10.287)
					)
					(stroke
						(width 0.254)
						(type default)
					)
					(fill
						(type background)
					)
				)
				(polyline
					(pts
						(xy 9.652 -11.303) (xy 11.43 -10.287) (xy 11.43 -12.319) (xy 9.652 -11.303)
					)
					(stroke
						(width 0.254)
						(type default)
					)
					(fill
						(type outline)
					)
				)
				(polyline
					(pts
						(xy 9.652 -16.383) (xy 7.874 -16.383) (xy 7.874 -15.367) (xy 6.096 -15.367)
					)
					(stroke
						(width 0.254)
						(type default)
					)
					(fill
						(type background)
					)
				)
				(polyline
					(pts
						(xy 9.652 -16.383) (xy 11.43 -15.367) (xy 11.43 -17.399) (xy 9.652 -16.383)
					)
					(stroke
						(width 0.254)
						(type default)
					)
					(fill
						(type outline)
					)
				)
				(polyline
					(pts
						(xy 9.652 -21.463) (xy 7.874 -21.463) (xy 7.874 -20.447) (xy 6.096 -20.447)
					)
					(stroke
						(width 0.254)
						(type default)
					)
					(fill
						(type background)
					)
				)
				(polyline
					(pts
						(xy 9.652 -21.463) (xy 11.43 -20.447) (xy 11.43 -22.479) (xy 9.652 -21.463)
					)
					(stroke
						(width 0.254)
						(type default)
					)
					(fill
						(type outline)
					)
				)
				(polyline
					(pts
						(xy 11.43 -4.191) (xy 9.652 -5.207) (xy 9.652 -3.175) (xy 11.43 -4.191)
					)
					(stroke
						(width 0.254)
						(type default)
					)
					(fill
						(type outline)
					)
				)
				(polyline
					(pts
						(xy 11.43 -4.191) (xy 13.208 -4.191) (xy 13.208 -5.207) (xy 14.478 -5.207)
					)
					(stroke
						(width 0.254)
						(type default)
					)
					(fill
						(type background)
					)
				)
				(polyline
					(pts
						(xy 11.43 -9.271) (xy 9.652 -10.287) (xy 9.652 -8.255) (xy 11.43 -9.271)
					)
					(stroke
						(width 0.254)
						(type default)
					)
					(fill
						(type outline)
					)
				)
				(polyline
					(pts
						(xy 11.43 -9.271) (xy 13.208 -9.271) (xy 13.208 -10.287) (xy 14.478 -10.287)
					)
					(stroke
						(width 0.254)
						(type default)
					)
					(fill
						(type background)
					)
				)
				(polyline
					(pts
						(xy 11.43 -14.351) (xy 9.652 -15.367) (xy 9.652 -13.335) (xy 11.43 -14.351)
					)
					(stroke
						(width 0.254)
						(type default)
					)
					(fill
						(type outline)
					)
				)
				(polyline
					(pts
						(xy 11.43 -14.351) (xy 13.208 -14.351) (xy 13.208 -15.367) (xy 14.478 -15.367)
					)
					(stroke
						(width 0.254)
						(type default)
					)
					(fill
						(type background)
					)
				)
				(polyline
					(pts
						(xy 11.43 -19.431) (xy 9.652 -20.447) (xy 9.652 -18.415) (xy 11.43 -19.431)
					)
					(stroke
						(width 0.254)
						(type default)
					)
					(fill
						(type outline)
					)
				)
				(polyline
					(pts
						(xy 11.43 -19.431) (xy 13.208 -19.431) (xy 13.208 -20.447) (xy 14.478 -20.447)
					)
					(stroke
						(width 0.254)
						(type default)
					)
					(fill
						(type background)
					)
				)
				(polyline
					(pts
						(xy 13.208 -5.207) (xy 13.208 -6.223) (xy 11.43 -6.223)
					)
					(stroke
						(width 0.254)
						(type default)
					)
					(fill
						(type background)
					)
				)
				(polyline
					(pts
						(xy 13.208 -10.287) (xy 13.208 -11.303) (xy 11.43 -11.303)
					)
					(stroke
						(width 0.254)
						(type default)
					)
					(fill
						(type background)
					)
				)
				(polyline
					(pts
						(xy 13.208 -15.367) (xy 13.208 -16.383) (xy 11.43 -16.383)
					)
					(stroke
						(width 0.254)
						(type default)
					)
					(fill
						(type background)
					)
				)
				(polyline
					(pts
						(xy 13.208 -20.447) (xy 13.208 -21.463) (xy 11.43 -21.463)
					)
					(stroke
						(width 0.254)
						(type default)
					)
					(fill
						(type background)
					)
				)
				(pin power_in line
					(at 0 0 0)
					(length 2.54)
					(name "VCCA"
						(effects
							(font
								(size 1.27 1.27)
							)
						)
					)
					(number "1"
						(effects
							(font
								(size 1.27 1.27)
							)
						)
					)
				)
				(pin tri_state line
					(at 0 -5.08 0)
					(length 2.54)
					(name "A1"
						(effects
							(font
								(size 1.27 1.27)
							)
						)
					)
					(number "2"
						(effects
							(font
								(size 1.27 1.27)
							)
						)
					)
				)
				(pin tri_state line
					(at 0 -10.16 0)
					(length 2.54)
					(name "A2"
						(effects
							(font
								(size 1.27 1.27)
							)
						)
					)
					(number "3"
						(effects
							(font
								(size 1.27 1.27)
							)
						)
					)
				)
				(pin tri_state line
					(at 0 -15.24 0)
					(length 2.54)
					(name "A3"
						(effects
							(font
								(size 1.27 1.27)
							)
						)
					)
					(number "4"
						(effects
							(font
								(size 1.27 1.27)
							)
						)
					)
				)
				(pin tri_state line
					(at 0 -20.32 0)
					(length 2.54)
					(name "A4"
						(effects
							(font
								(size 1.27 1.27)
							)
						)
					)
					(number "5"
						(effects
							(font
								(size 1.27 1.27)
							)
						)
					)
				)
				(pin input line
					(at 0 -25.4 0)
					(length 2.54)
					(name "OE"
						(effects
							(font
								(size 1.27 1.27)
							)
						)
					)
					(number "12"
						(effects
							(font
								(size 1.27 1.27)
							)
						)
					)
				)
				(pin power_in line
					(at 20.32 0 180)
					(length 2.54)
					(name "VCCB"
						(effects
							(font
								(size 1.27 1.27)
							)
						)
					)
					(number "11"
						(effects
							(font
								(size 1.27 1.27)
							)
						)
					)
				)
				(pin tri_state line
					(at 20.32 -5.08 180)
					(length 2.54)
					(name "B1"
						(effects
							(font
								(size 1.27 1.27)
							)
						)
					)
					(number "10"
						(effects
							(font
								(size 1.27 1.27)
							)
						)
					)
				)
				(pin tri_state line
					(at 20.32 -10.16 180)
					(length 2.54)
					(name "B2"
						(effects
							(font
								(size 1.27 1.27)
							)
						)
					)
					(number "9"
						(effects
							(font
								(size 1.27 1.27)
							)
						)
					)
				)
				(pin tri_state line
					(at 20.32 -15.24 180)
					(length 2.54)
					(name "B3"
						(effects
							(font
								(size 1.27 1.27)
							)
						)
					)
					(number "8"
						(effects
							(font
								(size 1.27 1.27)
							)
						)
					)
				)
				(pin tri_state line
					(at 20.32 -20.32 180)
					(length 2.54)
					(name "B4"
						(effects
							(font
								(size 1.27 1.27)
							)
						)
					)
					(number "7"
						(effects
							(font
								(size 1.27 1.27)
							)
						)
					)
				)
				(pin power_in line
					(at 20.32 -25.4 180)
					(length 2.54)
					(name "GND"
						(effects
							(font
								(size 1.27 1.27)
							)
						)
					)
					(number "6"
						(effects
							(font
								(size 1.27 1.27)
							)
						)
					)
				)
			)
		)
	(symbol "antmicroMechanicalParts:Spacer_Drill3.7mm_H2.5mm_9774025151R"
			(exclude_from_sim no)
			(in_bom yes)
			(on_board yes)
			(property "Reference" "H"
				(at 22.86 -2.54 0)
				(effects
					(font
						(size 1.27 1.27)
						(thickness 0.15)
					)
					(justify left bottom)
				)
			)
			(property "Value" "Spacer_Drill3.7mm_H2.5mm_9774025151R"
				(at 22.86 -5.08 0)
				(effects
					(font
						(size 1.27 1.27)
						(thickness 0.15)
					)
					(justify left bottom)
				)
			)
			(property "Footprint" "antmicro-footprints:Spacer_Drill3.7mm_H2.5mm_9774025151R"
				(at 22.86 -7.62 0)
				(effects
					(font
						(size 1.27 1.27)
						(thickness 0.15)
					)
					(justify left bottom)
					(hide yes)
				)
			)
			(property "Datasheet" "https://www.we-online.com/components/products/datasheet/9774025151R.pdf"
				(at 22.86 -10.16 0)
				(effects
					(font
						(size 1.27 1.27)
						(thickness 0.15)
					)
					(justify left bottom)
					(hide yes)
				)
			)
			(property "Description" "Spacer, SMT, Non Stop, Steel, Swage Round, 5.1 mm x 2.5 mm, M2.5 Thread, WA-SMSI Series"
				(at 0 0 0)
				(effects
					(font
						(size 1.27 1.27)
					)
					(hide yes)
				)
			)
			(property "Manufacturer" "Würth Elektronik"
				(at 22.86 -12.7 0)
				(effects
					(font
						(size 1.27 1.27)
						(thickness 0.15)
					)
					(justify left bottom)
					(hide yes)
				)
			)
			(property "MPN" "9774025151R"
				(at 22.86 -15.24 0)
				(effects
					(font
						(size 1.27 1.27)
						(thickness 0.15)
					)
					(justify left bottom)
					(hide yes)
				)
			)
			(property "Author" "Antmicro"
				(at 22.86 -17.78 0)
				(effects
					(font
						(size 1.27 1.27)
						(thickness 0.15)
					)
					(justify left bottom)
					(hide yes)
				)
			)
			(property "License" "Apache-2.0"
				(at 22.86 -20.32 0)
				(effects
					(font
						(size 1.27 1.27)
						(thickness 0.15)
					)
					(justify left bottom)
					(hide yes)
				)
			)
			(property "ki_keywords" "MECHANICAL, SPACER"
				(at 0 0 0)
				(effects
					(font
						(size 1.27 1.27)
					)
					(hide yes)
				)
			)
			(symbol "Spacer_Drill3.7mm_H2.5mm_9774025151R_1_1"
				(rectangle
					(start 2.54 -2.54)
					(end 7.62 2.54)
					(stroke
						(width 0.254)
						(type default)
					)
					(fill
						(type background)
					)
				)
				(rectangle
					(start 3.81 -1.27)
					(end 6.35 1.27)
					(stroke
						(width 0.254)
						(type default)
					)
					(fill
						(type background)
					)
				)
				(pin passive line
					(at 0 0 0)
					(length 2.54)
					(name "~"
						(effects
							(font
								(size 1.27 1.27)
							)
						)
					)
					(number "1"
						(effects
							(font
								(size 1.27 1.27)
							)
						)
					)
				)
			)
		)
	(symbol "antmicroMechanicalParts:Spacer_Drill3.7mm_H2mm_9774020151R"
			(exclude_from_sim no)
			(in_bom yes)
			(on_board yes)
			(property "Reference" "H"
				(at 22.86 -2.54 0)
				(effects
					(font
						(size 1.27 1.27)
						(thickness 0.15)
					)
					(justify left bottom)
				)
			)
			(property "Value" "Spacer_Drill3.7mm_H2mm_9774020151R"
				(at 22.86 -7.62 0)
				(effects
					(font
						(size 1.27 1.27)
						(thickness 0.15)
					)
					(justify left bottom)
					(hide yes)
				)
			)
			(property "Footprint" "antmicro-footprints:Spacer_Drill3.7mm_H2mm_9774020151R"
				(at 22.86 -10.16 0)
				(effects
					(font
						(size 1.27 1.27)
						(thickness 0.15)
					)
					(justify left bottom)
					(hide yes)
				)
			)
			(property "Datasheet" "https://www.we-online.com/components/products/datasheet/9774020151R.pdf"
				(at 22.86 -12.7 0)
				(effects
					(font
						(size 1.27 1.27)
						(thickness 0.15)
					)
					(justify left bottom)
					(hide yes)
				)
			)
			(property "Description" "Spacer, SMT, Non Stop, Steel, Swage Round, 5.1 mm x 2 mm, M2.5 Thread, WA-SMSI Series"
				(at 0 0 0)
				(effects
					(font
						(size 1.27 1.27)
					)
					(hide yes)
				)
			)
			(property "Manufacturer" "Würth Elektronik"
				(at 22.86 -15.24 0)
				(effects
					(font
						(size 1.27 1.27)
						(thickness 0.15)
					)
					(justify left bottom)
					(hide yes)
				)
			)
			(property "MPN" "9774020151R"
				(at 22.86 -5.08 0)
				(effects
					(font
						(size 1.27 1.27)
						(thickness 0.15)
					)
					(justify left bottom)
				)
			)
			(property "Author" "Antmicro"
				(at 22.86 -17.78 0)
				(effects
					(font
						(size 1.27 1.27)
						(thickness 0.15)
					)
					(justify left bottom)
					(hide yes)
				)
			)
			(property "License" "Apache-2.0"
				(at 22.86 -20.32 0)
				(effects
					(font
						(size 1.27 1.27)
						(thickness 0.15)
					)
					(justify left bottom)
					(hide yes)
				)
			)
			(property "ki_keywords" "MECHANICAL, SPACER"
				(at 0 0 0)
				(effects
					(font
						(size 1.27 1.27)
					)
					(hide yes)
				)
			)
			(symbol "Spacer_Drill3.7mm_H2mm_9774020151R_1_1"
				(rectangle
					(start 2.54 -2.54)
					(end 7.62 2.54)
					(stroke
						(width 0.254)
						(type default)
					)
					(fill
						(type background)
					)
				)
				(rectangle
					(start 3.81 -1.27)
					(end 6.35 1.27)
					(stroke
						(width 0.254)
						(type default)
					)
					(fill
						(type background)
					)
				)
				(pin passive line
					(at 0 0 0)
					(length 2.54)
					(name "~"
						(effects
							(font
								(size 1.27 1.27)
							)
						)
					)
					(number "1"
						(effects
							(font
								(size 1.27 1.27)
							)
						)
					)
				)
			)
		)
	(symbol "antmicroMechanicalParts:Spacer_Drill3.7mm_H3mm_9774030151R"
			(exclude_from_sim no)
			(in_bom yes)
			(on_board yes)
			(property "Reference" "H"
				(at 22.86 -2.54 0)
				(effects
					(font
						(size 1.27 1.27)
						(thickness 0.15)
					)
					(justify left bottom)
				)
			)
			(property "Value" "Spacer_Drill3.7mm_H3mm_9774030151R"
				(at 22.86 -5.08 0)
				(effects
					(font
						(size 1.27 1.27)
						(thickness 0.15)
					)
					(justify left bottom)
				)
			)
			(property "Footprint" "antmicro-footprints:Spacer_Drill3.7mm_H3mm_9774030151R"
				(at 22.86 -7.62 0)
				(effects
					(font
						(size 1.27 1.27)
						(thickness 0.15)
					)
					(justify left bottom)
					(hide yes)
				)
			)
			(property "Datasheet" "https://www.we-online.com/catalog/datasheet/9774030151.pdf"
				(at 22.86 -10.16 0)
				(effects
					(font
						(size 1.27 1.27)
						(thickness 0.15)
					)
					(justify left bottom)
					(hide yes)
				)
			)
			(property "Description" "Spacer, SMT,  Steel, Swage Round, 5.1mmx3mm, M3 Thread, WA-SMSI Series"
				(at 0 0 0)
				(effects
					(font
						(size 1.27 1.27)
					)
					(hide yes)
				)
			)
			(property "Manufacturer" "Würth Elektronik"
				(at 22.86 -12.7 0)
				(effects
					(font
						(size 1.27 1.27)
						(thickness 0.15)
					)
					(justify left bottom)
					(hide yes)
				)
			)
			(property "MPN" "9774030151R"
				(at 22.86 -15.24 0)
				(effects
					(font
						(size 1.27 1.27)
						(thickness 0.15)
					)
					(justify left bottom)
					(hide yes)
				)
			)
			(property "Author" "Antmicro"
				(at 22.86 -17.78 0)
				(effects
					(font
						(size 1.27 1.27)
						(thickness 0.15)
					)
					(justify left bottom)
					(hide yes)
				)
			)
			(property "License" "Apache-2.0"
				(at 22.86 -20.32 0)
				(effects
					(font
						(size 1.27 1.27)
						(thickness 0.15)
					)
					(justify left bottom)
					(hide yes)
				)
			)
			(property "ki_keywords" "SPACER"
				(at 0 0 0)
				(effects
					(font
						(size 1.27 1.27)
					)
					(hide yes)
				)
			)
			(symbol "Spacer_Drill3.7mm_H3mm_9774030151R_1_1"
				(rectangle
					(start 2.54 -2.54)
					(end 7.62 2.54)
					(stroke
						(width 0.254)
						(type default)
					)
					(fill
						(type background)
					)
				)
				(rectangle
					(start 3.81 -1.27)
					(end 6.35 1.27)
					(stroke
						(width 0.254)
						(type default)
					)
					(fill
						(type background)
					)
				)
				(pin passive line
					(at 0 0 0)
					(length 2.54)
					(name "~"
						(effects
							(font
								(size 1.27 1.27)
							)
						)
					)
					(number "1"
						(effects
							(font
								(size 1.27 1.27)
							)
						)
					)
				)
			)
		)
	(symbol "antmicroMechanicalParts:Spacer_Drill3.7mm_H6mm_9774060151R"
			(exclude_from_sim no)
			(in_bom yes)
			(on_board yes)
			(property "Reference" "H"
				(at 22.86 -2.54 0)
				(effects
					(font
						(size 1.27 1.27)
						(thickness 0.15)
					)
					(justify left bottom)
				)
			)
			(property "Value" "Spacer_Drill3.7mm_H6mm_9774060151R"
				(at 22.86 -5.08 0)
				(effects
					(font
						(size 1.27 1.27)
						(thickness 0.15)
					)
					(justify left bottom)
					(hide yes)
				)
			)
			(property "Footprint" "antmicro-footprints:Spacer_Drill3.7mm_H6mm_9774060151R"
				(at 22.86 -7.62 0)
				(effects
					(font
						(size 1.27 1.27)
						(thickness 0.15)
					)
					(justify left bottom)
					(hide yes)
				)
			)
			(property "Datasheet" "https://www.we-online.com/components/products/datasheet/9774060151R.pdf"
				(at 22.86 -10.16 0)
				(effects
					(font
						(size 1.27 1.27)
						(thickness 0.15)
					)
					(justify left bottom)
					(hide yes)
				)
			)
			(property "Description" "Spacer, SMT, Non Stop, Steel, Swage Round, 5.1 mm x 6 mm, M2.5 Thread, WA-SMSI Series"
				(at 0 0 0)
				(effects
					(font
						(size 1.27 1.27)
					)
					(hide yes)
				)
			)
			(property "Manufacturer" "Würth Elektronik"
				(at 22.86 -12.7 0)
				(effects
					(font
						(size 1.27 1.27)
						(thickness 0.15)
					)
					(justify left bottom)
					(hide yes)
				)
			)
			(property "MPN" "9774060151R"
				(at 22.86 -15.24 0)
				(effects
					(font
						(size 1.27 1.27)
						(thickness 0.15)
					)
					(justify left bottom)
				)
			)
			(property "Author" "Antmicro"
				(at 22.86 -17.78 0)
				(effects
					(font
						(size 1.27 1.27)
						(thickness 0.15)
					)
					(justify left bottom)
					(hide yes)
				)
			)
			(property "License" "Apache-2.0"
				(at 22.86 -20.32 0)
				(effects
					(font
						(size 1.27 1.27)
						(thickness 0.15)
					)
					(justify left bottom)
					(hide yes)
				)
			)
			(property "ki_keywords" "MECHANICAL, SPACER"
				(at 0 0 0)
				(effects
					(font
						(size 1.27 1.27)
					)
					(hide yes)
				)
			)
			(symbol "Spacer_Drill3.7mm_H6mm_9774060151R_1_1"
				(rectangle
					(start 2.54 -2.54)
					(end 7.62 2.54)
					(stroke
						(width 0.254)
						(type default)
					)
					(fill
						(type background)
					)
				)
				(rectangle
					(start 3.81 -1.27)
					(end 6.35 1.27)
					(stroke
						(width 0.254)
						(type default)
					)
					(fill
						(type background)
					)
				)
				(pin passive line
					(at 0 0 0)
					(length 2.54)
					(name "~"
						(effects
							(font
								(size 1.27 1.27)
							)
						)
					)
					(number "1"
						(effects
							(font
								(size 1.27 1.27)
							)
						)
					)
				)
			)
		)
	(symbol "antmicroMemory:93AA66C_SOIC"
			(exclude_from_sim no)
			(in_bom yes)
			(on_board yes)
			(property "Reference" "U"
				(at 35.56 -1.27 0)
				(effects
					(font
						(size 1.27 1.27)
						(thickness 0.15)
					)
					(justify left bottom)
				)
			)
			(property "Value" "93AA66C_SOIC"
				(at 35.56 -6.35 0)
				(effects
					(font
						(size 1.27 1.27)
						(thickness 0.15)
					)
					(justify left bottom)
					(hide yes)
				)
			)
			(property "Footprint" "antmicro-footprints:SOIC-8_3.9x4.9x1.75mm_P1.27mm"
				(at 35.56 -8.89 0)
				(effects
					(font
						(size 1.27 1.27)
						(thickness 0.15)
					)
					(justify left bottom)
					(hide yes)
				)
			)
			(property "Datasheet" "https://ww1.microchip.com/downloads/aemDocuments/documents/MPD/ProductDocuments/DataSheets/93AA66X-93LC66X-93C66X-4-Kbit-Microwire-Compatible-Serial-EEPROM-Data-Sheet.pdf"
				(at 35.56 -11.43 0)
				(effects
					(font
						(size 1.27 1.27)
						(thickness 0.15)
					)
					(justify left bottom)
					(hide yes)
				)
			)
			(property "Description" "EEPROM 512x8 Or 256x16"
				(at 0 0 0)
				(effects
					(font
						(size 1.27 1.27)
					)
					(hide yes)
				)
			)
			(property "MPN" "93AA66C-I/SN"
				(at 35.56 -3.81 0)
				(effects
					(font
						(size 1.27 1.27)
					)
					(justify left bottom)
				)
			)
			(property "Manufacturer" "Microchip Technology"
				(at 35.56 -19.05 0)
				(effects
					(font
						(size 1.27 1.27)
					)
					(justify left bottom)
					(hide yes)
				)
			)
			(property "Author" "Antmicro"
				(at 35.56 -13.97 0)
				(effects
					(font
						(size 1.27 1.27)
						(thickness 0.15)
					)
					(justify left bottom)
					(hide yes)
				)
			)
			(property "License" "Apache-2.0"
				(at 35.56 -16.51 0)
				(effects
					(font
						(size 1.27 1.27)
						(thickness 0.15)
					)
					(justify left bottom)
					(hide yes)
				)
			)
			(property "ki_keywords" "SMT, MEMORY, IC, EEPROM"
				(at 0 0 0)
				(effects
					(font
						(size 1.27 1.27)
					)
					(hide yes)
				)
			)
			(property "ki_fp_filters" "DIP*W7.62mm* SOIC*3.9x4.9mm*"
				(at 0 0 0)
				(effects
					(font
						(size 1.27 1.27)
					)
					(hide yes)
				)
			)
			(symbol "93AA66C_SOIC_1_1"
				(rectangle
					(start 2.54 2.54)
					(end 13.97 -10.16)
					(stroke
						(width 0.254)
						(type default)
					)
					(fill
						(type background)
					)
				)
				(pin power_in line
					(at 0 0 0)
					(length 2.54)
					(name "VCC"
						(effects
							(font
								(size 1.27 1.27)
							)
						)
					)
					(number "8"
						(effects
							(font
								(size 1.27 1.27)
							)
						)
					)
				)
				(pin input line
					(at 0 -5.08 0)
					(length 2.54)
					(name "ORG"
						(effects
							(font
								(size 1.27 1.27)
							)
						)
					)
					(number "6"
						(effects
							(font
								(size 1.27 1.27)
							)
						)
					)
				)
				(pin power_in line
					(at 0 -7.62 0)
					(length 2.54)
					(name "GND"
						(effects
							(font
								(size 1.27 1.27)
							)
						)
					)
					(number "5"
						(effects
							(font
								(size 1.27 1.27)
							)
						)
					)
				)
				(pin no_connect line
					(at 2.54 -2.54 0)
					(length 2.54)
					(hide yes)
					(name "NC"
						(effects
							(font
								(size 1.27 1.27)
							)
						)
					)
					(number "7"
						(effects
							(font
								(size 1.27 1.27)
							)
						)
					)
				)
				(pin input line
					(at 16.51 0 180)
					(length 2.54)
					(name "CS"
						(effects
							(font
								(size 1.27 1.27)
							)
						)
					)
					(number "1"
						(effects
							(font
								(size 1.27 1.27)
							)
						)
					)
				)
				(pin input line
					(at 16.51 -2.54 180)
					(length 2.54)
					(name "CLK"
						(effects
							(font
								(size 1.27 1.27)
							)
						)
					)
					(number "2"
						(effects
							(font
								(size 1.27 1.27)
							)
						)
					)
				)
				(pin input line
					(at 16.51 -5.08 180)
					(length 2.54)
					(name "DI"
						(effects
							(font
								(size 1.27 1.27)
							)
						)
					)
					(number "3"
						(effects
							(font
								(size 1.27 1.27)
							)
						)
					)
				)
				(pin tri_state line
					(at 16.51 -7.62 180)
					(length 2.54)
					(name "DO"
						(effects
							(font
								(size 1.27 1.27)
							)
						)
					)
					(number "4"
						(effects
							(font
								(size 1.27 1.27)
							)
						)
					)
				)
			)
		)
	(symbol "antmicroMemoryConnectorsPCCardSockets:MicroSD_1140084168"
			(exclude_from_sim no)
			(in_bom yes)
			(on_board yes)
			(property "Reference" "J"
				(at 38.1 -3.81 0)
				(effects
					(font
						(size 1.27 1.27)
						(thickness 0.15)
					)
					(justify left bottom)
				)
			)
			(property "Value" "MicroSD_1140084168"
				(at 38.1 -6.35 0)
				(effects
					(font
						(size 1.27 1.27)
						(thickness 0.15)
					)
					(justify left bottom)
					(hide yes)
				)
			)
			(property "Footprint" "antmicro-footprints:MicroSD_Amphenol_1140084168"
				(at 38.1 -8.89 0)
				(effects
					(font
						(size 1.27 1.27)
						(thickness 0.15)
					)
					(justify left bottom)
					(hide yes)
				)
			)
			(property "Datasheet" "https://cdn.amphenol-cs.com/media/wysiwyg/files/documentation/datasheet/inputoutput/io_micro_sdcard.pdf"
				(at 38.1 -11.43 0)
				(effects
					(font
						(size 1.27 1.27)
						(thickness 0.15)
					)
					(justify left bottom)
					(hide yes)
				)
			)
			(property "Description" "Memory Card Connector, MicroSD, Push-Pull, 8 Contacts, Copper Alloy, Gold Plated Contacts"
				(at 0 0 0)
				(effects
					(font
						(size 1.27 1.27)
					)
					(hide yes)
				)
			)
			(property "MPN" "1140084168"
				(at 38.1 -13.97 0)
				(effects
					(font
						(size 1.27 1.27)
						(thickness 0.15)
					)
					(justify left bottom)
				)
			)
			(property "Manufacturer" "Amphenol"
				(at 38.1 -16.51 0)
				(effects
					(font
						(size 1.27 1.27)
						(thickness 0.15)
					)
					(justify left bottom)
					(hide yes)
				)
			)
			(property "Author" "Antmicro"
				(at 38.1 -19.05 0)
				(effects
					(font
						(size 1.27 1.27)
						(thickness 0.15)
					)
					(justify left bottom)
					(hide yes)
				)
			)
			(property "License" "Apache-2.0"
				(at 38.1 -21.59 0)
				(effects
					(font
						(size 1.27 1.27)
						(thickness 0.15)
					)
					(justify left bottom)
					(hide yes)
				)
			)
			(property "ki_keywords" "HORIZONTAL, SMT, MEMORY, CONNECTOR, MICRO"
				(at 0 0 0)
				(effects
					(font
						(size 1.27 1.27)
					)
					(hide yes)
				)
			)
			(symbol "MicroSD_1140084168_1_1"
				(polyline
					(pts
						(xy 2.54 2.54) (xy 2.54 -24.13) (xy 10.16 -24.13) (xy 13.97 -24.13) (xy 19.05 -24.13) (xy 19.05 -16.51)
						(xy 24.13 -11.43) (xy 24.13 2.54) (xy 2.54 2.54)
					)
					(stroke
						(width 0.254)
						(type default)
					)
					(fill
						(type background)
					)
				)
				(text "microSD CARD"
					(at 19.05 -12.7 900)
					(effects
						(font
							(size 1.27 1.27)
							(thickness 0.15)
						)
						(justify left bottom)
					)
				)
				(pin bidirectional line
					(at 0 0 0)
					(length 2.54)
					(name "DAT2"
						(effects
							(font
								(size 1.27 1.27)
							)
						)
					)
					(number "1"
						(effects
							(font
								(size 1.27 1.27)
							)
						)
					)
				)
				(pin bidirectional line
					(at 0 -2.54 0)
					(length 2.54)
					(name "CD/DAT3"
						(effects
							(font
								(size 1.27 1.27)
							)
						)
					)
					(number "2"
						(effects
							(font
								(size 1.27 1.27)
							)
						)
					)
				)
				(pin bidirectional line
					(at 0 -5.08 0)
					(length 2.54)
					(name "CMD"
						(effects
							(font
								(size 1.27 1.27)
							)
						)
					)
					(number "3"
						(effects
							(font
								(size 1.27 1.27)
							)
						)
					)
				)
				(pin power_in line
					(at 0 -7.62 0)
					(length 2.54)
					(name "VDD"
						(effects
							(font
								(size 1.27 1.27)
							)
						)
					)
					(number "4"
						(effects
							(font
								(size 1.27 1.27)
							)
						)
					)
				)
				(pin output line
					(at 0 -10.16 0)
					(length 2.54)
					(name "CLK"
						(effects
							(font
								(size 1.27 1.27)
							)
						)
					)
					(number "5"
						(effects
							(font
								(size 1.27 1.27)
							)
						)
					)
				)
				(pin power_in line
					(at 0 -12.7 0)
					(length 2.54)
					(name "VSS"
						(effects
							(font
								(size 1.27 1.27)
							)
						)
					)
					(number "6"
						(effects
							(font
								(size 1.27 1.27)
							)
						)
					)
				)
				(pin bidirectional line
					(at 0 -15.24 0)
					(length 2.54)
					(name "DAT0"
						(effects
							(font
								(size 1.27 1.27)
							)
						)
					)
					(number "7"
						(effects
							(font
								(size 1.27 1.27)
							)
						)
					)
				)
				(pin bidirectional line
					(at 0 -17.78 0)
					(length 2.54)
					(name "DAT1"
						(effects
							(font
								(size 1.27 1.27)
							)
						)
					)
					(number "8"
						(effects
							(font
								(size 1.27 1.27)
							)
						)
					)
				)
				(pin passive line
					(at 0 -20.32 0)
					(length 2.54)
					(name "CD1"
						(effects
							(font
								(size 1.27 1.27)
							)
						)
					)
					(number "9"
						(effects
							(font
								(size 1.27 1.27)
							)
						)
					)
				)
				(pin passive line
					(at 0 -22.86 0)
					(length 2.54)
					(name "CD2"
						(effects
							(font
								(size 1.27 1.27)
							)
						)
					)
					(number "10"
						(effects
							(font
								(size 1.27 1.27)
							)
						)
					)
				)
				(pin passive line
					(at 21.59 -20.32 180)
					(length 2.54)
					(name "Shell"
						(effects
							(font
								(size 1.27 1.27)
							)
						)
					)
					(number "SH"
						(effects
							(font
								(size 1.27 1.27)
							)
						)
					)
				)
			)
		)
	(symbol "antmicroModularConnectorsJacksWithMagnetics:Bus_RJ45_5-2337992-8"
			(exclude_from_sim no)
			(in_bom yes)
			(on_board yes)
			(property "Reference" "J"
				(at 35.56 -2.54 0)
				(effects
					(font
						(size 1.27 1.27)
						(thickness 0.15)
					)
					(justify left bottom)
				)
			)
			(property "Value" "Bus_RJ45_5-2337992-8"
				(at 35.56 -5.08 0)
				(effects
					(font
						(size 1.27 1.27)
						(thickness 0.15)
					)
					(justify left bottom)
					(hide yes)
				)
			)
			(property "Footprint" "antmicro-footprints:RJ45_X-2337992-8_Horizontal"
				(at 35.56 -7.62 0)
				(effects
					(font
						(size 1.27 1.27)
						(thickness 0.15)
					)
					(justify left bottom)
					(hide yes)
				)
			)
			(property "Datasheet" "https://www.te.com/commerce/DocumentDelivery/DDEController?Action=showdoc&DocId=Customer+Drawing%7F5-2337992-8%7FA%7Fpdf%7FEnglish%7FENG_CD_5-2337992-8_A.pdf%7F5-2337992-8"
				(at 35.56 -10.16 0)
				(effects
					(font
						(size 1.27 1.27)
						(thickness 0.15)
					)
					(justify left bottom)
					(hide yes)
				)
			)
			(property "Description" "Modular Connector, RJ45 Jack, 1 x 1 (Port), 8P8C, Cat5e, Through Hole Mount"
				(at 0 0 0)
				(effects
					(font
						(size 1.27 1.27)
					)
					(hide yes)
				)
			)
			(property "MPN" "5-2337992-8"
				(at 35.56 -12.7 0)
				(effects
					(font
						(size 1.27 1.27)
						(thickness 0.15)
					)
					(justify left bottom)
				)
			)
			(property "Manufacturer" "TE Connectivity"
				(at 35.56 -15.24 0)
				(effects
					(font
						(size 1.27 1.27)
						(thickness 0.15)
					)
					(justify left bottom)
					(hide yes)
				)
			)
			(property "Author" "Antmicro"
				(at 35.56 -17.78 0)
				(effects
					(font
						(size 1.27 1.27)
						(thickness 0.15)
					)
					(justify left bottom)
					(hide yes)
				)
			)
			(property "License" "Apache-2.0"
				(at 35.56 -20.32 0)
				(effects
					(font
						(size 1.27 1.27)
						(thickness 0.15)
					)
					(justify left bottom)
					(hide yes)
				)
			)
			(property "ki_keywords" "RJ45, HORIZONTAL, THT, ETHERNET, CONNECTOR, FEMALE"
				(at 0 0 0)
				(effects
					(font
						(size 1.27 1.27)
					)
					(hide yes)
				)
			)
			(property "ki_fp_filters" "CONN18_5-2337992-8_TEC"
				(at 0 0 0)
				(effects
					(font
						(size 1.27 1.27)
					)
					(hide yes)
				)
			)
			(symbol "Bus_RJ45_5-2337992-8_1_1"
				(rectangle
					(start 2.54 2.54)
					(end 19.05 -38.1)
					(stroke
						(width 0.254)
						(type default)
					)
					(fill
						(type background)
					)
				)
				(polyline
					(pts
						(xy 8.89 -1.27) (xy 8.89 -13.97)
					)
					(stroke
						(width 0.254)
						(type default)
					)
					(fill
						(type background)
					)
				)
				(polyline
					(pts
						(xy 8.89 -1.27) (xy 13.97 -1.27)
					)
					(stroke
						(width 0.254)
						(type default)
					)
					(fill
						(type background)
					)
				)
				(polyline
					(pts
						(xy 8.89 -13.97) (xy 13.97 -13.97)
					)
					(stroke
						(width 0.254)
						(type default)
					)
					(fill
						(type background)
					)
				)
				(polyline
					(pts
						(xy 13.97 -1.27) (xy 13.97 -2.54)
					)
					(stroke
						(width 0.254)
						(type default)
					)
					(fill
						(type background)
					)
				)
				(polyline
					(pts
						(xy 13.97 -2.54) (xy 15.24 -2.54)
					)
					(stroke
						(width 0.254)
						(type default)
					)
					(fill
						(type background)
					)
				)
				(polyline
					(pts
						(xy 13.97 -12.7) (xy 15.24 -12.7)
					)
					(stroke
						(width 0.254)
						(type default)
					)
					(fill
						(type background)
					)
				)
				(polyline
					(pts
						(xy 13.97 -13.97) (xy 13.97 -12.7)
					)
					(stroke
						(width 0.254)
						(type default)
					)
					(fill
						(type background)
					)
				)
				(polyline
					(pts
						(xy 15.24 -2.54) (xy 15.24 -3.81)
					)
					(stroke
						(width 0.254)
						(type default)
					)
					(fill
						(type background)
					)
				)
				(polyline
					(pts
						(xy 15.24 -3.81) (xy 16.51 -3.81)
					)
					(stroke
						(width 0.254)
						(type default)
					)
					(fill
						(type background)
					)
				)
				(polyline
					(pts
						(xy 15.24 -11.43) (xy 16.51 -11.43)
					)
					(stroke
						(width 0.254)
						(type default)
					)
					(fill
						(type background)
					)
				)
				(polyline
					(pts
						(xy 15.24 -12.7) (xy 15.24 -11.43)
					)
					(stroke
						(width 0.254)
						(type default)
					)
					(fill
						(type background)
					)
				)
				(polyline
					(pts
						(xy 16.51 -3.81) (xy 16.51 -11.43)
					)
					(stroke
						(width 0.254)
						(type default)
					)
					(fill
						(type background)
					)
				)
				(pin bidirectional line
					(at 0 0 0)
					(length 2.54)
					(name "P1"
						(effects
							(font
								(size 1.27 1.27)
							)
						)
					)
					(number "1"
						(effects
							(font
								(size 1.27 1.27)
							)
						)
					)
				)
				(pin bidirectional line
					(at 0 -2.54 0)
					(length 2.54)
					(name "P2"
						(effects
							(font
								(size 1.27 1.27)
							)
						)
					)
					(number "2"
						(effects
							(font
								(size 1.27 1.27)
							)
						)
					)
				)
				(pin bidirectional line
					(at 0 -5.08 0)
					(length 2.54)
					(name "P3"
						(effects
							(font
								(size 1.27 1.27)
							)
						)
					)
					(number "3"
						(effects
							(font
								(size 1.27 1.27)
							)
						)
					)
				)
				(pin bidirectional line
					(at 0 -7.62 0)
					(length 2.54)
					(name "P6"
						(effects
							(font
								(size 1.27 1.27)
							)
						)
					)
					(number "6"
						(effects
							(font
								(size 1.27 1.27)
							)
						)
					)
				)
				(pin bidirectional line
					(at 0 -10.16 0)
					(length 2.54)
					(name "P7"
						(effects
							(font
								(size 1.27 1.27)
							)
						)
					)
					(number "7"
						(effects
							(font
								(size 1.27 1.27)
							)
						)
					)
				)
				(pin bidirectional line
					(at 0 -12.7 0)
					(length 2.54)
					(name "P8"
						(effects
							(font
								(size 1.27 1.27)
							)
						)
					)
					(number "8"
						(effects
							(font
								(size 1.27 1.27)
							)
						)
					)
				)
				(pin bidirectional line
					(at 0 -15.24 0)
					(length 2.54)
					(name "P9"
						(effects
							(font
								(size 1.27 1.27)
							)
						)
					)
					(number "9"
						(effects
							(font
								(size 1.27 1.27)
							)
						)
					)
				)
				(pin bidirectional line
					(at 0 -17.78 0)
					(length 2.54)
					(name "P10"
						(effects
							(font
								(size 1.27 1.27)
							)
						)
					)
					(number "10"
						(effects
							(font
								(size 1.27 1.27)
							)
						)
					)
				)
				(pin bidirectional line
					(at 0 -22.86 0)
					(length 2.54)
					(name "P4"
						(effects
							(font
								(size 1.27 1.27)
							)
						)
					)
					(number "4"
						(effects
							(font
								(size 1.27 1.27)
							)
						)
					)
				)
				(pin bidirectional line
					(at 0 -25.4 0)
					(length 2.54)
					(name "P5"
						(effects
							(font
								(size 1.27 1.27)
							)
						)
					)
					(number "5"
						(effects
							(font
								(size 1.27 1.27)
							)
						)
					)
				)
				(pin bidirectional line
					(at 0 -27.94 0)
					(length 2.54)
					(name "VC1"
						(effects
							(font
								(size 1.27 1.27)
							)
						)
					)
					(number "11"
						(effects
							(font
								(size 1.27 1.27)
							)
						)
					)
				)
				(pin bidirectional line
					(at 0 -30.48 0)
					(length 2.54)
					(name "VC2"
						(effects
							(font
								(size 1.27 1.27)
							)
						)
					)
					(number "12"
						(effects
							(font
								(size 1.27 1.27)
							)
						)
					)
				)
				(pin bidirectional line
					(at 0 -33.02 0)
					(length 2.54)
					(name "VC3"
						(effects
							(font
								(size 1.27 1.27)
							)
						)
					)
					(number "13"
						(effects
							(font
								(size 1.27 1.27)
							)
						)
					)
				)
				(pin bidirectional line
					(at 0 -35.56 0)
					(length 2.54)
					(name "VC4"
						(effects
							(font
								(size 1.27 1.27)
							)
						)
					)
					(number "14"
						(effects
							(font
								(size 1.27 1.27)
							)
						)
					)
				)
				(pin passive line
					(at 21.59 -22.86 180)
					(length 2.54)
					(name "LED_YEL+"
						(effects
							(font
								(size 1.27 1.27)
							)
						)
					)
					(number "17"
						(effects
							(font
								(size 1.27 1.27)
							)
						)
					)
				)
				(pin passive line
					(at 21.59 -25.4 180)
					(length 2.54)
					(name "LED_YEL-"
						(effects
							(font
								(size 1.27 1.27)
							)
						)
					)
					(number "18"
						(effects
							(font
								(size 1.27 1.27)
							)
						)
					)
				)
				(pin passive line
					(at 21.59 -27.94 180)
					(length 2.54)
					(name "LED_GRN+"
						(effects
							(font
								(size 1.27 1.27)
							)
						)
					)
					(number "15"
						(effects
							(font
								(size 1.27 1.27)
							)
						)
					)
				)
				(pin passive line
					(at 21.59 -30.48 180)
					(length 2.54)
					(name "LED_GRN-"
						(effects
							(font
								(size 1.27 1.27)
							)
						)
					)
					(number "16"
						(effects
							(font
								(size 1.27 1.27)
							)
						)
					)
				)
				(pin passive line
					(at 21.59 -35.56 180)
					(length 2.54)
					(name "SHIELD"
						(effects
							(font
								(size 1.27 1.27)
							)
						)
					)
					(number "19"
						(effects
							(font
								(size 1.27 1.27)
							)
						)
					)
				)
				(pin passive line
					(at 21.59 -35.56 180)
					(length 2.54)
					(hide yes)
					(name "SHIELD"
						(effects
							(font
								(size 1.27 1.27)
							)
						)
					)
					(number "20"
						(effects
							(font
								(size 1.27 1.27)
							)
						)
					)
				)
			)
		)
	(symbol "antmicroModules:Compute-Module-4_H1.5mm"
			(exclude_from_sim no)
			(in_bom no)
			(on_board yes)
			(property "Reference" "A"
				(at 17.78 -2.54 0)
				(effects
					(font
						(size 1.27 1.27)
						(thickness 0.15)
					)
					(justify left bottom)
				)
			)
			(property "Value" "Compute-Module-4_H1.5mm"
				(at 17.78 -5.08 0)
				(effects
					(font
						(size 1.27 1.27)
						(thickness 0.15)
					)
					(justify left bottom)
					(hide yes)
				)
			)
			(property "Footprint" "antmicro-footprints:Compute-Module-4_H1.5mm"
				(at 17.78 -7.62 0)
				(effects
					(font
						(size 1.27 1.27)
						(thickness 0.15)
					)
					(justify left bottom)
					(hide yes)
				)
			)
			(property "Datasheet" "https://datasheets.raspberrypi.com/cm4/cm4-datasheet.pdf"
				(at 17.78 -10.16 0)
				(effects
					(font
						(size 1.27 1.27)
						(thickness 0.15)
					)
					(justify left bottom)
					(hide yes)
				)
			)
			(property "Description" "Raspberry PI, Compute Module 4"
				(at 0 0 0)
				(effects
					(font
						(size 1.27 1.27)
					)
					(hide yes)
				)
			)
			(property "Manufacturer" "Raspberry Pi"
				(at 17.78 -12.7 0)
				(effects
					(font
						(size 1.27 1.27)
						(thickness 0.15)
					)
					(justify left bottom)
					(hide yes)
				)
			)
			(property "MPN" "SC0294"
				(at 21.59 -20.32 0)
				(effects
					(font
						(size 1.27 1.27)
					)
				)
			)
			(property "Author" "Antmicro"
				(at 17.78 -15.24 0)
				(effects
					(font
						(size 1.27 1.27)
						(thickness 0.15)
					)
					(justify left bottom)
					(hide yes)
				)
			)
			(property "License" "Apache-2.0"
				(at 17.78 -17.78 0)
				(effects
					(font
						(size 1.27 1.27)
						(thickness 0.15)
					)
					(justify left bottom)
					(hide yes)
				)
			)
			(property "ki_keywords" "MODULE, B2B"
				(at 0 0 0)
				(effects
					(font
						(size 1.27 1.27)
					)
					(hide yes)
				)
			)
			(symbol "Compute-Module-4_H1.5mm_1_1"
				(rectangle
					(start 10.16 -6.35)
					(end 0 0)
					(stroke
						(width 0.254)
						(type default)
					)
					(fill
						(type background)
					)
				)
			)
		)
	(symbol "antmicroModules:Mech_M2_2280_H2.5mm"
			(exclude_from_sim no)
			(in_bom no)
			(on_board yes)
			(property "Reference" "A"
				(at 25.4 0 0)
				(effects
					(font
						(size 1.27 1.27)
						(thickness 0.15)
					)
					(justify left bottom)
				)
			)
			(property "Value" "Mech_M2_2280_H2.5mm"
				(at 25.4 -2.54 0)
				(effects
					(font
						(size 1.27 1.27)
						(thickness 0.15)
					)
					(justify left bottom)
				)
			)
			(property "Footprint" "antmicro-footprints:Mech_M2_2280_H2.5mm"
				(at 25.4 -5.08 0)
				(effects
					(font
						(size 1.27 1.27)
						(thickness 0.15)
					)
					(justify left bottom)
					(hide yes)
				)
			)
			(property "Datasheet" ""
				(at 25.4 -7.62 0)
				(effects
					(font
						(size 1.27 1.27)
						(thickness 0.15)
					)
					(justify left bottom)
					(hide yes)
				)
			)
			(property "Description" "Mechanical model for M2 2280 2.5mm module"
				(at 0 0 0)
				(effects
					(font
						(size 1.27 1.27)
					)
					(hide yes)
				)
			)
			(property "Manufacturer" ""
				(at 0 0 0)
				(effects
					(font
						(size 1.27 1.27)
					)
					(hide yes)
				)
			)
			(property "MPN" ""
				(at 0 0 0)
				(effects
					(font
						(size 1.27 1.27)
					)
				)
			)
			(property "Author" "Antmicro"
				(at 25.4 -10.16 0)
				(effects
					(font
						(size 1.27 1.27)
						(thickness 0.15)
					)
					(justify left bottom)
					(hide yes)
				)
			)
			(property "License" "Apache-2.0"
				(at 25.4 -12.7 0)
				(effects
					(font
						(size 1.27 1.27)
						(thickness 0.15)
					)
					(justify left bottom)
					(hide yes)
				)
			)
			(property "ki_keywords" "MODULE"
				(at 0 0 0)
				(effects
					(font
						(size 1.27 1.27)
					)
					(hide yes)
				)
			)
			(symbol "Mech_M2_2280_H2.5mm_1_1"
				(rectangle
					(start 10.16 -6.35)
					(end 0 0)
					(stroke
						(width 0.254)
						(type default)
					)
					(fill
						(type background)
					)
				)
			)
		)
	(symbol "antmicroOptoisolatorsLogicOutput:ACPL-217-500E"
			(exclude_from_sim no)
			(in_bom yes)
			(on_board yes)
			(property "Reference" "U"
				(at 27.94 -5.08 0)
				(effects
					(font
						(size 1.27 1.27)
						(thickness 0.15)
					)
					(justify left bottom)
				)
			)
			(property "Value" "ACPL-217-500E"
				(at 27.94 -7.62 0)
				(effects
					(font
						(size 1.27 1.27)
						(thickness 0.15)
					)
					(justify left bottom)
					(hide yes)
				)
			)
			(property "Footprint" "antmicro-footprints:SOIC-4_4.55x2.6mm_P1.27mm"
				(at 27.94 -10.16 0)
				(effects
					(font
						(size 1.27 1.27)
						(thickness 0.15)
					)
					(justify left bottom)
					(hide yes)
				)
			)
			(property "Datasheet" "https://docs.broadcom.com/doc/AV02-0470EN"
				(at 27.94 -12.7 0)
				(effects
					(font
						(size 1.27 1.27)
						(thickness 0.15)
					)
					(justify left bottom)
					(hide yes)
				)
			)
			(property "Description" "Optocoupler, Transistor Output, 1 Channel, SOIC, 4 Pins, 50 mA, 3 kV, 50 %"
				(at 27.94 -15.24 0)
				(effects
					(font
						(size 1.27 1.27)
						(thickness 0.15)
					)
					(justify left bottom)
					(hide yes)
				)
			)
			(property "Manufacturer" "Broadcom"
				(at 27.94 -17.78 0)
				(effects
					(font
						(size 1.27 1.27)
						(thickness 0.15)
					)
					(justify left bottom)
					(hide yes)
				)
			)
			(property "MPN" "ACPL-217-500E"
				(at 27.94 -20.32 0)
				(effects
					(font
						(size 1.27 1.27)
						(thickness 0.15)
					)
					(justify left bottom)
				)
			)
			(property "Author" "Antmicro"
				(at 27.94 -22.86 0)
				(effects
					(font
						(size 1.27 1.27)
						(thickness 0.15)
					)
					(justify left bottom)
					(hide yes)
				)
			)
			(property "License" "Apache-2.0"
				(at 27.94 -25.4 0)
				(effects
					(font
						(size 1.27 1.27)
						(thickness 0.15)
					)
					(justify left bottom)
					(hide yes)
				)
			)
			(property "ki_keywords" "SMT, OPTOCOUPLER, IC"
				(at 0 0 0)
				(effects
					(font
						(size 1.27 1.27)
					)
					(hide yes)
				)
			)
			(symbol "ACPL-217-500E_1_1"
				(rectangle
					(start 2.54 1.27)
					(end 10.414 -5.08)
					(stroke
						(width 0.254)
						(type default)
					)
					(fill
						(type background)
					)
				)
				(rectangle
					(start 2.54 0.635)
					(end 2.54 0.635)
					(stroke
						(width 0.254)
						(type default)
					)
					(fill
						(type background)
					)
				)
				(polyline
					(pts
						(xy 2.54 0) (xy 3.81 0) (xy 3.81 -1.27)
					)
					(stroke
						(width 0.254)
						(type default)
					)
					(fill
						(type background)
					)
				)
				(polyline
					(pts
						(xy 2.54 -3.81) (xy 3.81 -3.81) (xy 3.81 -2.54)
					)
					(stroke
						(width 0.254)
						(type default)
					)
					(fill
						(type background)
					)
				)
				(polyline
					(pts
						(xy 3.175 -1.27) (xy 4.445 -1.27) (xy 3.81 -2.413) (xy 3.175 -1.27)
					)
					(stroke
						(width 0.254)
						(type default)
					)
					(fill
						(type background)
					)
				)
				(polyline
					(pts
						(xy 3.175 -2.413) (xy 4.445 -2.413)
					)
					(stroke
						(width 0.254)
						(type default)
					)
					(fill
						(type background)
					)
				)
				(polyline
					(pts
						(xy 5.207 -1.397) (xy 7.239 -1.397)
					)
					(stroke
						(width 0.254)
						(type default)
					)
					(fill
						(type background)
					)
				)
				(polyline
					(pts
						(xy 5.207 -2.413) (xy 7.239 -2.413)
					)
					(stroke
						(width 0.254)
						(type default)
					)
					(fill
						(type background)
					)
				)
				(polyline
					(pts
						(xy 6.477 -1.143) (xy 6.477 -1.143) (xy 6.477 -1.651) (xy 7.239 -1.397) (xy 6.477 -1.143) (xy 6.477 -1.143)
					)
					(stroke
						(width 0.254)
						(type default)
					)
					(fill
						(type background)
					)
				)
				(polyline
					(pts
						(xy 6.477 -2.159) (xy 6.477 -2.159) (xy 6.477 -2.667) (xy 7.239 -2.413) (xy 6.477 -2.159) (xy 6.477 -2.159)
					)
					(stroke
						(width 0.254)
						(type default)
					)
					(fill
						(type background)
					)
				)
				(polyline
					(pts
						(xy 7.747 -0.889) (xy 7.747 -2.921)
					)
					(stroke
						(width 0.254)
						(type default)
					)
					(fill
						(type background)
					)
				)
				(polyline
					(pts
						(xy 9.017 -0.127) (xy 7.747 -1.397)
					)
					(stroke
						(width 0.254)
						(type default)
					)
					(fill
						(type background)
					)
				)
				(polyline
					(pts
						(xy 9.017 -3.683) (xy 7.747 -2.413)
					)
					(stroke
						(width 0.254)
						(type default)
					)
					(fill
						(type background)
					)
				)
				(polyline
					(pts
						(xy 9.017 -3.683) (xy 9.017 -3.683) (xy 8.89 -3.048) (xy 8.382 -3.556) (xy 9.017 -3.683) (xy 9.017 -3.683)
					)
					(stroke
						(width 0.254)
						(type default)
					)
					(fill
						(type background)
					)
				)
				(polyline
					(pts
						(xy 9.144 0) (xy 7.874 -1.27)
					)
					(stroke
						(width 0.254)
						(type default)
					)
					(fill
						(type background)
					)
				)
				(polyline
					(pts
						(xy 9.144 -3.81) (xy 8.89 -3.556)
					)
					(stroke
						(width 0.254)
						(type default)
					)
					(fill
						(type background)
					)
				)
				(polyline
					(pts
						(xy 9.144 -3.81) (xy 8.89 -3.556)
					)
					(stroke
						(width 0.254)
						(type default)
					)
					(fill
						(type background)
					)
				)
				(polyline
					(pts
						(xy 10.414 0) (xy 9.144 0)
					)
					(stroke
						(width 0.254)
						(type default)
					)
					(fill
						(type background)
					)
				)
				(polyline
					(pts
						(xy 10.414 -3.81) (xy 9.144 -3.81)
					)
					(stroke
						(width 0.254)
						(type default)
					)
					(fill
						(type background)
					)
				)
				(pin passive line
					(at 0 0 0)
					(length 2.54)
					(name "~"
						(effects
							(font
								(size 1.27 1.27)
							)
						)
					)
					(number "1"
						(effects
							(font
								(size 1.27 1.27)
							)
						)
					)
				)
				(pin passive line
					(at 0 -3.81 0)
					(length 2.54)
					(name "~"
						(effects
							(font
								(size 1.27 1.27)
							)
						)
					)
					(number "2"
						(effects
							(font
								(size 1.27 1.27)
							)
						)
					)
				)
				(pin passive line
					(at 12.7 0 180)
					(length 2.54)
					(name "~"
						(effects
							(font
								(size 1.27 1.27)
							)
						)
					)
					(number "4"
						(effects
							(font
								(size 1.27 1.27)
							)
						)
					)
				)
				(pin passive line
					(at 12.7 -3.81 180)
					(length 2.54)
					(name "~"
						(effects
							(font
								(size 1.27 1.27)
							)
						)
					)
					(number "3"
						(effects
							(font
								(size 1.27 1.27)
							)
						)
					)
				)
			)
		)
	(symbol "antmicroPMICORControllersIdealDiodes:DZDH0401DW"
			(exclude_from_sim no)
			(in_bom yes)
			(on_board yes)
			(property "Reference" "Q"
				(at 30.48 -5.08 0)
				(effects
					(font
						(size 1.27 1.27)
						(thickness 0.15)
					)
					(justify left bottom)
				)
			)
			(property "Value" "DZDH0401DW"
				(at 30.48 -7.62 0)
				(effects
					(font
						(size 1.27 1.27)
						(thickness 0.15)
					)
					(justify left bottom)
					(hide yes)
				)
			)
			(property "Footprint" "antmicro-footprints:SOT-363"
				(at 30.48 -10.16 0)
				(effects
					(font
						(size 1.27 1.27)
						(thickness 0.15)
					)
					(justify left bottom)
					(hide yes)
				)
			)
			(property "Datasheet" "https://www.mouser.com/datasheet/2/115/DIOD_S_A0011803041_1-2543705.pdf"
				(at 30.48 -12.7 0)
				(effects
					(font
						(size 1.27 1.27)
						(thickness 0.15)
					)
					(justify left bottom)
					(hide yes)
				)
			)
			(property "Description" "OR Controller N+1 ORing Controller P-Channel 1:1 SOT-363"
				(at 0 0 0)
				(effects
					(font
						(size 1.27 1.27)
					)
					(hide yes)
				)
			)
			(property "MPN" "DZDH0401DW"
				(at 30.48 -15.24 0)
				(effects
					(font
						(size 1.27 1.27)
						(thickness 0.15)
					)
					(justify left bottom)
				)
			)
			(property "Manufacturer" "Diodes Incorporated"
				(at 30.48 -17.78 0)
				(effects
					(font
						(size 1.27 1.27)
						(thickness 0.15)
					)
					(justify left bottom)
					(hide yes)
				)
			)
			(property "Author" "Antmicro"
				(at 30.48 -20.32 0)
				(effects
					(font
						(size 1.27 1.27)
						(thickness 0.15)
					)
					(justify left bottom)
					(hide yes)
				)
			)
			(property "License" "Apache-2.0"
				(at 30.48 -22.86 0)
				(effects
					(font
						(size 1.27 1.27)
						(thickness 0.15)
					)
					(justify left bottom)
					(hide yes)
				)
			)
			(property "ki_keywords" "SMT, CONTROLLER, SEMICONDUCTOR, DIODE, PMOS"
				(at 0 0 0)
				(effects
					(font
						(size 1.27 1.27)
					)
					(hide yes)
				)
			)
			(symbol "DZDH0401DW_1_0"
				(pin no_connect line
					(at 2.54 -3.81 0)
					(length 2.54)
					(hide yes)
					(name "NC"
						(effects
							(font
								(size 1.27 1.27)
							)
						)
					)
					(number "1"
						(effects
							(font
								(size 1.27 1.27)
							)
						)
					)
				)
				(pin no_connect line
					(at 13.97 -3.81 180)
					(length 2.54)
					(hide yes)
					(name "NC"
						(effects
							(font
								(size 1.27 1.27)
							)
						)
					)
					(number "5"
						(effects
							(font
								(size 1.27 1.27)
							)
						)
					)
				)
			)
			(symbol "DZDH0401DW_1_1"
				(rectangle
					(start 2.54 2.54)
					(end 13.97 -5.08)
					(stroke
						(width 0.254)
						(type default)
					)
					(fill
						(type background)
					)
				)
				(pin power_in line
					(at 0 0 0)
					(length 2.54)
					(name "D"
						(effects
							(font
								(size 1.27 1.27)
							)
						)
					)
					(number "6"
						(effects
							(font
								(size 1.27 1.27)
							)
						)
					)
				)
				(pin input line
					(at 0 -2.54 0)
					(length 2.54)
					(name "REF"
						(effects
							(font
								(size 1.27 1.27)
							)
						)
					)
					(number "2"
						(effects
							(font
								(size 1.27 1.27)
							)
						)
					)
				)
				(pin power_in line
					(at 16.51 0 180)
					(length 2.54)
					(name "S"
						(effects
							(font
								(size 1.27 1.27)
							)
						)
					)
					(number "4"
						(effects
							(font
								(size 1.27 1.27)
							)
						)
					)
				)
				(pin output line
					(at 16.51 -2.54 180)
					(length 2.54)
					(name "BIAS"
						(effects
							(font
								(size 1.27 1.27)
							)
						)
					)
					(number "3"
						(effects
							(font
								(size 1.27 1.27)
							)
						)
					)
				)
			)
		)
	(symbol "antmicroPMICPowerDistributionSwitchesLoadDrivers:AP22615A_TSOT26"
			(exclude_from_sim no)
			(in_bom yes)
			(on_board yes)
			(property "Reference" "U"
				(at 30.48 -2.54 0)
				(effects
					(font
						(size 1.27 1.27)
						(thickness 0.15)
					)
					(justify left bottom)
				)
			)
			(property "Value" "AP22615A_TSOT26"
				(at 30.48 -5.08 0)
				(effects
					(font
						(size 1.27 1.27)
						(thickness 0.15)
					)
					(justify left bottom)
					(hide yes)
				)
			)
			(property "Footprint" "antmicro-footprints:TSOT23-6"
				(at 30.48 -7.62 0)
				(effects
					(font
						(size 1.27 1.27)
						(thickness 0.15)
					)
					(justify left bottom)
					(hide yes)
				)
			)
			(property "Datasheet" "https://www.mouser.com/datasheet/2/115/DIOD_S_A0008958405_1-2543193.pdf"
				(at 30.48 -10.16 0)
				(effects
					(font
						(size 1.27 1.27)
						(thickness 0.15)
					)
					(justify left bottom)
					(hide yes)
				)
			)
			(property "Description" "Power Load Distribution Switch, High Side, Active High, 1 Output, 5.5 V, 3.6 A, 0.04 ohm, TSOT-26-6"
				(at 0 0 0)
				(effects
					(font
						(size 1.27 1.27)
					)
					(hide yes)
				)
			)
			(property "MPN" "AP22615AWU-7"
				(at 30.48 -12.7 0)
				(effects
					(font
						(size 1.27 1.27)
						(thickness 0.15)
					)
					(justify left bottom)
				)
			)
			(property "Manufacturer" "Diodes Incorporated"
				(at 30.48 -15.24 0)
				(effects
					(font
						(size 1.27 1.27)
						(thickness 0.15)
					)
					(justify left bottom)
					(hide yes)
				)
			)
			(property "Author" "Antmicro"
				(at 30.48 -17.78 0)
				(effects
					(font
						(size 1.27 1.27)
						(thickness 0.15)
					)
					(justify left bottom)
					(hide yes)
				)
			)
			(property "License" "Apache-2.0"
				(at 30.48 -20.32 0)
				(effects
					(font
						(size 1.27 1.27)
						(thickness 0.15)
					)
					(justify left bottom)
					(hide yes)
				)
			)
			(property "ki_keywords" "SMT, PMIC, IC, VOLTAGE"
				(at 0 0 0)
				(effects
					(font
						(size 1.27 1.27)
					)
					(hide yes)
				)
			)
			(symbol "AP22615A_TSOT26_1_1"
				(rectangle
					(start 2.54 2.54)
					(end 12.7 -7.62)
					(stroke
						(width 0.254)
						(type default)
					)
					(fill
						(type background)
					)
				)
				(pin power_in line
					(at 0 0 0)
					(length 2.54)
					(name "IN"
						(effects
							(font
								(size 1.27 1.27)
							)
						)
					)
					(number "6"
						(effects
							(font
								(size 1.27 1.27)
							)
						)
					)
				)
				(pin output line
					(at 0 -2.54 0)
					(length 2.54)
					(name "FLG"
						(effects
							(font
								(size 1.27 1.27)
							)
						)
					)
					(number "3"
						(effects
							(font
								(size 1.27 1.27)
							)
						)
					)
				)
				(pin input line
					(at 0 -5.08 0)
					(length 2.54)
					(name "EN"
						(effects
							(font
								(size 1.27 1.27)
							)
						)
					)
					(number "4"
						(effects
							(font
								(size 1.27 1.27)
							)
						)
					)
				)
				(pin power_out line
					(at 15.24 0 180)
					(length 2.54)
					(name "OUT"
						(effects
							(font
								(size 1.27 1.27)
							)
						)
					)
					(number "1"
						(effects
							(font
								(size 1.27 1.27)
							)
						)
					)
				)
				(pin passive line
					(at 15.24 -2.54 180)
					(length 2.54)
					(name "ISET"
						(effects
							(font
								(size 1.27 1.27)
							)
						)
					)
					(number "5"
						(effects
							(font
								(size 1.27 1.27)
							)
						)
					)
				)
				(pin power_in line
					(at 15.24 -5.08 180)
					(length 2.54)
					(name "GND"
						(effects
							(font
								(size 1.27 1.27)
							)
						)
					)
					(number "2"
						(effects
							(font
								(size 1.27 1.27)
							)
						)
					)
				)
			)
		)
	(symbol "antmicroPMICPowerDistributionSwitchesLoadDrivers:TPS2372-3RGWR"
			(exclude_from_sim no)
			(in_bom yes)
			(on_board yes)
			(property "Reference" "U"
				(at 35.56 0 0)
				(effects
					(font
						(size 1.27 1.27)
						(thickness 0.15)
					)
					(justify left bottom)
				)
			)
			(property "Value" "TPS2372-3RGWR"
				(at 35.56 -2.54 0)
				(effects
					(font
						(size 1.27 1.27)
						(thickness 0.15)
					)
					(justify left bottom)
					(hide yes)
				)
			)
			(property "Footprint" "antmicro-footprints:VQFN-20_5x5x1mm_P0.65mm"
				(at 35.56 -5.08 0)
				(effects
					(font
						(size 1.27 1.27)
						(thickness 0.15)
					)
					(justify left bottom)
					(hide yes)
				)
			)
			(property "Datasheet" "https://www.ti.com/lit/ds/symlink/tps2372.pdf?ts=1679042478513&ref_url=https%253A%252F%252Fwww.google.com%252F"
				(at 35.56 -7.62 0)
				(effects
					(font
						(size 1.27 1.27)
						(thickness 0.15)
					)
					(justify left bottom)
					(hide yes)
				)
			)
			(property "Description" "PoE interface"
				(at 0 0 0)
				(effects
					(font
						(size 1.27 1.27)
					)
					(hide yes)
				)
			)
			(property "MPN" "TPS2372-3RGWR"
				(at 35.56 -10.16 0)
				(effects
					(font
						(size 1.27 1.27)
						(thickness 0.15)
					)
					(justify left bottom)
				)
			)
			(property "Manufacturer" "Texas Instruments"
				(at 35.56 -12.7 0)
				(effects
					(font
						(size 1.27 1.27)
						(thickness 0.15)
					)
					(justify left bottom)
					(hide yes)
				)
			)
			(property "Author" "Antmicro"
				(at 35.56 -15.24 0)
				(effects
					(font
						(size 1.27 1.27)
						(thickness 0.15)
					)
					(justify left bottom)
					(hide yes)
				)
			)
			(property "License" "Apache-2.0"
				(at 35.56 -17.78 0)
				(effects
					(font
						(size 1.27 1.27)
						(thickness 0.15)
					)
					(justify left bottom)
					(hide yes)
				)
			)
			(property "ki_keywords" "SMT, POE, IC, INTERFACE"
				(at 0 0 0)
				(effects
					(font
						(size 1.27 1.27)
					)
					(hide yes)
				)
			)
			(symbol "TPS2372-3RGWR_1_1"
				(rectangle
					(start 2.54 2.54)
					(end 19.05 -35.56)
					(stroke
						(width 0.254)
						(type default)
					)
					(fill
						(type background)
					)
				)
				(pin power_in line
					(at 0 0 0)
					(length 2.54)
					(name "VDD"
						(effects
							(font
								(size 1.27 1.27)
							)
						)
					)
					(number "1"
						(effects
							(font
								(size 1.27 1.27)
							)
						)
					)
				)
				(pin input line
					(at 0 -2.54 0)
					(length 2.54)
					(name "DEN"
						(effects
							(font
								(size 1.27 1.27)
							)
						)
					)
					(number "2"
						(effects
							(font
								(size 1.27 1.27)
							)
						)
					)
				)
				(pin input line
					(at 0 -7.62 0)
					(length 2.54)
					(name "CLSA"
						(effects
							(font
								(size 1.27 1.27)
							)
						)
					)
					(number "3"
						(effects
							(font
								(size 1.27 1.27)
							)
						)
					)
				)
				(pin input line
					(at 0 -10.16 0)
					(length 2.54)
					(name "CLSB"
						(effects
							(font
								(size 1.27 1.27)
							)
						)
					)
					(number "6"
						(effects
							(font
								(size 1.27 1.27)
							)
						)
					)
				)
				(pin power_in line
					(at 0 -15.24 0)
					(length 2.54)
					(name "VSSA"
						(effects
							(font
								(size 1.27 1.27)
							)
						)
					)
					(number "4"
						(effects
							(font
								(size 1.27 1.27)
							)
						)
					)
				)
				(pin power_in line
					(at 0 -17.78 0)
					(length 2.54)
					(name "VSSB"
						(effects
							(font
								(size 1.27 1.27)
							)
						)
					)
					(number "5"
						(effects
							(font
								(size 1.27 1.27)
							)
						)
					)
				)
				(pin power_in line
					(at 0 -20.32 0)
					(length 2.54)
					(name "PAD_VSSC"
						(effects
							(font
								(size 1.27 1.27)
							)
						)
					)
					(number "21"
						(effects
							(font
								(size 1.27 1.27)
							)
						)
					)
				)
				(pin input line
					(at 0 -22.86 0)
					(length 2.54)
					(name "AMPS_CTL"
						(effects
							(font
								(size 1.27 1.27)
							)
						)
					)
					(number "8"
						(effects
							(font
								(size 1.27 1.27)
							)
						)
					)
				)
				(pin input line
					(at 0 -25.4 0)
					(length 2.54)
					(name "REF"
						(effects
							(font
								(size 1.27 1.27)
							)
						)
					)
					(number "7"
						(effects
							(font
								(size 1.27 1.27)
							)
						)
					)
				)
				(pin input line
					(at 0 -27.94 0)
					(length 2.54)
					(name "MPS_DUTY"
						(effects
							(font
								(size 1.27 1.27)
							)
						)
					)
					(number "9"
						(effects
							(font
								(size 1.27 1.27)
							)
						)
					)
				)
				(pin input line
					(at 0 -33.02 0)
					(length 2.54)
					(name "~{AUTCLS}"
						(effects
							(font
								(size 1.27 1.27)
							)
						)
					)
					(number "10"
						(effects
							(font
								(size 1.27 1.27)
							)
						)
					)
				)
				(pin no_connect line
					(at 19.05 -10.16 180)
					(length 2.54)
					(hide yes)
					(name "NC"
						(effects
							(font
								(size 1.27 1.27)
							)
						)
					)
					(number "20"
						(effects
							(font
								(size 1.27 1.27)
							)
						)
					)
				)
				(pin no_connect line
					(at 19.05 -12.7 180)
					(length 2.54)
					(hide yes)
					(name "NC"
						(effects
							(font
								(size 1.27 1.27)
							)
						)
					)
					(number "15"
						(effects
							(font
								(size 1.27 1.27)
							)
						)
					)
				)
				(pin no_connect line
					(at 19.05 -15.24 180)
					(length 2.54)
					(hide yes)
					(name "NC"
						(effects
							(font
								(size 1.27 1.27)
							)
						)
					)
					(number "14"
						(effects
							(font
								(size 1.27 1.27)
							)
						)
					)
				)
				(pin output line
					(at 21.59 0 180)
					(length 2.54)
					(name "TPH"
						(effects
							(font
								(size 1.27 1.27)
							)
						)
					)
					(number "18"
						(effects
							(font
								(size 1.27 1.27)
							)
						)
					)
				)
				(pin output line
					(at 21.59 -2.54 180)
					(length 2.54)
					(name "TPL"
						(effects
							(font
								(size 1.27 1.27)
							)
						)
					)
					(number "17"
						(effects
							(font
								(size 1.27 1.27)
							)
						)
					)
				)
				(pin output line
					(at 21.59 -5.08 180)
					(length 2.54)
					(name "~{BT}"
						(effects
							(font
								(size 1.27 1.27)
							)
						)
					)
					(number "19"
						(effects
							(font
								(size 1.27 1.27)
							)
						)
					)
				)
				(pin output line
					(at 21.59 -20.32 180)
					(length 2.54)
					(name "PG"
						(effects
							(font
								(size 1.27 1.27)
							)
						)
					)
					(number "13"
						(effects
							(font
								(size 1.27 1.27)
							)
						)
					)
				)
				(pin output line
					(at 21.59 -25.4 180)
					(length 2.54)
					(name "IRSHDL_EN"
						(effects
							(font
								(size 1.27 1.27)
							)
						)
					)
					(number "16"
						(effects
							(font
								(size 1.27 1.27)
							)
						)
					)
				)
				(pin power_out line
					(at 21.59 -30.48 180)
					(length 2.54)
					(name "RTNA"
						(effects
							(font
								(size 1.27 1.27)
							)
						)
					)
					(number "11"
						(effects
							(font
								(size 1.27 1.27)
							)
						)
					)
				)
				(pin power_out line
					(at 21.59 -33.02 180)
					(length 2.54)
					(name "RTNB"
						(effects
							(font
								(size 1.27 1.27)
							)
						)
					)
					(number "12"
						(effects
							(font
								(size 1.27 1.27)
							)
						)
					)
				)
			)
		)
	(symbol "antmicroPciConnectors:Bus_M.2_1-2199230-6"
			(exclude_from_sim no)
			(in_bom yes)
			(on_board yes)
			(property "Reference" "J"
				(at 45.72 -2.54 0)
				(effects
					(font
						(size 1.27 1.27)
						(thickness 0.15)
					)
					(justify left bottom)
				)
			)
			(property "Value" "Bus_M.2_1-2199230-6"
				(at 45.72 -7.62 0)
				(effects
					(font
						(size 1.27 1.27)
						(thickness 0.15)
					)
					(justify left bottom)
					(hide yes)
				)
			)
			(property "Footprint" "antmicro-footprints:Bus_M.2_Socket_Key_M_TE_1-2199230-6"
				(at 45.72 -10.16 0)
				(effects
					(font
						(size 1.27 1.27)
						(thickness 0.15)
					)
					(justify left bottom)
					(hide yes)
				)
			)
			(property "Datasheet" "https://www.te.com/commerce/DocumentDelivery/DDEController?Action=srchrtrv&DocNm=2199230&DocType=Customer+Drawing&DocLang=English"
				(at 45.72 -12.7 0)
				(effects
					(font
						(size 1.27 1.27)
						(thickness 0.15)
					)
					(justify left bottom)
					(hide yes)
				)
			)
			(property "Description" "Key M Card Edge Connector, 0, Dual Side, 67 Contacts, Surface Mount, Right Angle, Solder"
				(at 0 0 0)
				(effects
					(font
						(size 1.27 1.27)
					)
					(hide yes)
				)
			)
			(property "Manufacturer" "TE Connectivity"
				(at 45.72 -15.24 0)
				(effects
					(font
						(size 1.27 1.27)
						(thickness 0.15)
					)
					(justify left bottom)
					(hide yes)
				)
			)
			(property "MPN" "1-2199230-6"
				(at 45.72 -5.08 0)
				(effects
					(font
						(size 1.27 1.27)
						(thickness 0.15)
					)
					(justify left bottom)
				)
			)
			(property "Author" "Antmicro"
				(at 45.72 -17.78 0)
				(effects
					(font
						(size 1.27 1.27)
						(thickness 0.15)
					)
					(justify left bottom)
					(hide yes)
				)
			)
			(property "License" "Apache-2.0"
				(at 45.72 -20.32 0)
				(effects
					(font
						(size 1.27 1.27)
						(thickness 0.15)
					)
					(justify left bottom)
					(hide yes)
				)
			)
			(property "ki_keywords" "HORIZONTAL, SMT, PCIE, CONNECTOR"
				(at 0 0 0)
				(effects
					(font
						(size 1.27 1.27)
					)
					(hide yes)
				)
			)
			(symbol "Bus_M.2_1-2199230-6_0_0"
				(text "KEY M"
					(at 15.24 0 0)
					(effects
						(font
							(size 1.27 1.27)
							(bold yes)
						)
					)
				)
			)
			(symbol "Bus_M.2_1-2199230-6_1_1"
				(rectangle
					(start 3.81 2.54)
					(end 26.67 -80.01)
					(stroke
						(width 0.254)
						(type default)
					)
					(fill
						(type background)
					)
				)
				(pin input line
					(at 0 0 0)
					(length 3.81)
					(name "~{PERST}"
						(effects
							(font
								(size 1.27 1.27)
							)
						)
					)
					(number "50"
						(effects
							(font
								(size 1.27 1.27)
							)
						)
					)
				)
				(pin output line
					(at 0 -2.54 0)
					(length 3.81)
					(name "~{CLKREQ}"
						(effects
							(font
								(size 1.27 1.27)
							)
						)
					)
					(number "52"
						(effects
							(font
								(size 1.27 1.27)
							)
						)
					)
				)
				(pin input line
					(at 0 -5.08 0)
					(length 3.81)
					(name "~{PEWAKE}"
						(effects
							(font
								(size 1.27 1.27)
							)
						)
					)
					(number "54"
						(effects
							(font
								(size 1.27 1.27)
							)
						)
					)
				)
				(pin input line
					(at 0 -12.7 0)
					(length 3.81)
					(name "REFCLK_P"
						(effects
							(font
								(size 1.27 1.27)
							)
						)
					)
					(number "55"
						(effects
							(font
								(size 1.27 1.27)
							)
						)
					)
				)
				(pin input line
					(at 0 -15.24 0)
					(length 3.81)
					(name "REFCLK_N"
						(effects
							(font
								(size 1.27 1.27)
							)
						)
					)
					(number "53"
						(effects
							(font
								(size 1.27 1.27)
							)
						)
					)
				)
				(pin input line
					(at 0 -21.59 0)
					(length 3.81)
					(name "PET0_P"
						(effects
							(font
								(size 1.27 1.27)
							)
						)
					)
					(number "49"
						(effects
							(font
								(size 1.27 1.27)
							)
						)
					)
				)
				(pin input line
					(at 0 -24.13 0)
					(length 3.81)
					(name "PET0_N"
						(effects
							(font
								(size 1.27 1.27)
							)
						)
					)
					(number "47"
						(effects
							(font
								(size 1.27 1.27)
							)
						)
					)
				)
				(pin output line
					(at 0 -29.21 0)
					(length 3.81)
					(name "PER0_P"
						(effects
							(font
								(size 1.27 1.27)
							)
						)
					)
					(number "43"
						(effects
							(font
								(size 1.27 1.27)
							)
						)
					)
				)
				(pin output line
					(at 0 -31.75 0)
					(length 3.81)
					(name "PER0_N"
						(effects
							(font
								(size 1.27 1.27)
							)
						)
					)
					(number "41"
						(effects
							(font
								(size 1.27 1.27)
							)
						)
					)
				)
				(pin input line
					(at 0 -36.83 0)
					(length 3.81)
					(name "PET1_P"
						(effects
							(font
								(size 1.27 1.27)
							)
						)
					)
					(number "37"
						(effects
							(font
								(size 1.27 1.27)
							)
						)
					)
				)
				(pin input line
					(at 0 -39.37 0)
					(length 3.81)
					(name "PET1_N"
						(effects
							(font
								(size 1.27 1.27)
							)
						)
					)
					(number "35"
						(effects
							(font
								(size 1.27 1.27)
							)
						)
					)
				)
				(pin output line
					(at 0 -44.45 0)
					(length 3.81)
					(name "PER1_P"
						(effects
							(font
								(size 1.27 1.27)
							)
						)
					)
					(number "31"
						(effects
							(font
								(size 1.27 1.27)
							)
						)
					)
				)
				(pin output line
					(at 0 -46.99 0)
					(length 3.81)
					(name "PER1_N"
						(effects
							(font
								(size 1.27 1.27)
							)
						)
					)
					(number "29"
						(effects
							(font
								(size 1.27 1.27)
							)
						)
					)
				)
				(pin input line
					(at 0 -52.07 0)
					(length 3.81)
					(name "PET2_P"
						(effects
							(font
								(size 1.27 1.27)
							)
						)
					)
					(number "25"
						(effects
							(font
								(size 1.27 1.27)
							)
						)
					)
				)
				(pin input line
					(at 0 -54.61 0)
					(length 3.81)
					(name "PET2_N"
						(effects
							(font
								(size 1.27 1.27)
							)
						)
					)
					(number "23"
						(effects
							(font
								(size 1.27 1.27)
							)
						)
					)
				)
				(pin output line
					(at 0 -59.69 0)
					(length 3.81)
					(name "PER2_P"
						(effects
							(font
								(size 1.27 1.27)
							)
						)
					)
					(number "19"
						(effects
							(font
								(size 1.27 1.27)
							)
						)
					)
				)
				(pin output line
					(at 0 -62.23 0)
					(length 3.81)
					(name "PER2_N"
						(effects
							(font
								(size 1.27 1.27)
							)
						)
					)
					(number "17"
						(effects
							(font
								(size 1.27 1.27)
							)
						)
					)
				)
				(pin input line
					(at 0 -67.31 0)
					(length 3.81)
					(name "PET3_P"
						(effects
							(font
								(size 1.27 1.27)
							)
						)
					)
					(number "13"
						(effects
							(font
								(size 1.27 1.27)
							)
						)
					)
				)
				(pin input line
					(at 0 -69.85 0)
					(length 3.81)
					(name "PET3_N"
						(effects
							(font
								(size 1.27 1.27)
							)
						)
					)
					(number "11"
						(effects
							(font
								(size 1.27 1.27)
							)
						)
					)
				)
				(pin output line
					(at 0 -74.93 0)
					(length 3.81)
					(name "PER3_P"
						(effects
							(font
								(size 1.27 1.27)
							)
						)
					)
					(number "7"
						(effects
							(font
								(size 1.27 1.27)
							)
						)
					)
				)
				(pin output line
					(at 0 -77.47 0)
					(length 3.81)
					(name "PER3_N"
						(effects
							(font
								(size 1.27 1.27)
							)
						)
					)
					(number "5"
						(effects
							(font
								(size 1.27 1.27)
							)
						)
					)
				)
				(pin no_connect line
					(at 26.67 -38.1 180)
					(length 3.81)
					(hide yes)
					(name "NC"
						(effects
							(font
								(size 1.27 1.27)
							)
						)
					)
					(number "69"
						(effects
							(font
								(size 1.27 1.27)
							)
						)
					)
				)
				(pin no_connect line
					(at 26.67 -39.37 180)
					(length 3.81)
					(hide yes)
					(name "NC"
						(effects
							(font
								(size 1.27 1.27)
							)
						)
					)
					(number "6"
						(effects
							(font
								(size 1.27 1.27)
							)
						)
					)
				)
				(pin no_connect line
					(at 26.67 -40.64 180)
					(length 3.81)
					(hide yes)
					(name "NC"
						(effects
							(font
								(size 1.27 1.27)
							)
						)
					)
					(number "67"
						(effects
							(font
								(size 1.27 1.27)
							)
						)
					)
				)
				(pin no_connect line
					(at 26.67 -41.91 180)
					(length 3.81)
					(hide yes)
					(name "NC"
						(effects
							(font
								(size 1.27 1.27)
							)
						)
					)
					(number "48"
						(effects
							(font
								(size 1.27 1.27)
							)
						)
					)
				)
				(pin no_connect line
					(at 26.67 -43.18 180)
					(length 3.81)
					(hide yes)
					(name "NC"
						(effects
							(font
								(size 1.27 1.27)
							)
						)
					)
					(number "56"
						(effects
							(font
								(size 1.27 1.27)
							)
						)
					)
				)
				(pin no_connect line
					(at 26.67 -44.45 180)
					(length 3.81)
					(hide yes)
					(name "NC"
						(effects
							(font
								(size 1.27 1.27)
							)
						)
					)
					(number "20"
						(effects
							(font
								(size 1.27 1.27)
							)
						)
					)
				)
				(pin no_connect line
					(at 26.67 -45.72 180)
					(length 3.81)
					(hide yes)
					(name "NC"
						(effects
							(font
								(size 1.27 1.27)
							)
						)
					)
					(number "22"
						(effects
							(font
								(size 1.27 1.27)
							)
						)
					)
				)
				(pin no_connect line
					(at 26.67 -46.99 180)
					(length 3.81)
					(hide yes)
					(name "NC"
						(effects
							(font
								(size 1.27 1.27)
							)
						)
					)
					(number "24"
						(effects
							(font
								(size 1.27 1.27)
							)
						)
					)
				)
				(pin no_connect line
					(at 26.67 -59.69 180)
					(length 3.81)
					(hide yes)
					(name "NC"
						(effects
							(font
								(size 1.27 1.27)
							)
						)
					)
					(number "26"
						(effects
							(font
								(size 1.27 1.27)
							)
						)
					)
				)
				(pin no_connect line
					(at 26.67 -60.96 180)
					(length 3.81)
					(hide yes)
					(name "NC"
						(effects
							(font
								(size 1.27 1.27)
							)
						)
					)
					(number "28"
						(effects
							(font
								(size 1.27 1.27)
							)
						)
					)
				)
				(pin no_connect line
					(at 26.67 -62.23 180)
					(length 3.81)
					(hide yes)
					(name "NC"
						(effects
							(font
								(size 1.27 1.27)
							)
						)
					)
					(number "30"
						(effects
							(font
								(size 1.27 1.27)
							)
						)
					)
				)
				(pin no_connect line
					(at 26.67 -63.5 180)
					(length 3.81)
					(hide yes)
					(name "NC"
						(effects
							(font
								(size 1.27 1.27)
							)
						)
					)
					(number "32"
						(effects
							(font
								(size 1.27 1.27)
							)
						)
					)
				)
				(pin no_connect line
					(at 26.67 -64.77 180)
					(length 3.81)
					(hide yes)
					(name "NC"
						(effects
							(font
								(size 1.27 1.27)
							)
						)
					)
					(number "8"
						(effects
							(font
								(size 1.27 1.27)
							)
						)
					)
				)
				(pin no_connect line
					(at 26.67 -66.04 180)
					(length 3.81)
					(hide yes)
					(name "NC"
						(effects
							(font
								(size 1.27 1.27)
							)
						)
					)
					(number "34"
						(effects
							(font
								(size 1.27 1.27)
							)
						)
					)
				)
				(pin no_connect line
					(at 26.67 -67.31 180)
					(length 3.81)
					(hide yes)
					(name "NC"
						(effects
							(font
								(size 1.27 1.27)
							)
						)
					)
					(number "36"
						(effects
							(font
								(size 1.27 1.27)
							)
						)
					)
				)
				(pin no_connect line
					(at 26.67 -68.58 180)
					(length 3.81)
					(hide yes)
					(name "NC"
						(effects
							(font
								(size 1.27 1.27)
							)
						)
					)
					(number "46"
						(effects
							(font
								(size 1.27 1.27)
							)
						)
					)
				)
				(pin no_connect line
					(at 26.67 -69.85 180)
					(length 3.81)
					(hide yes)
					(name "NC"
						(effects
							(font
								(size 1.27 1.27)
							)
						)
					)
					(number "38"
						(effects
							(font
								(size 1.27 1.27)
							)
						)
					)
				)
				(pin no_connect line
					(at 26.67 -71.12 180)
					(length 3.81)
					(hide yes)
					(name "NC"
						(effects
							(font
								(size 1.27 1.27)
							)
						)
					)
					(number "58"
						(effects
							(font
								(size 1.27 1.27)
							)
						)
					)
				)
				(pin passive line
					(at 30.48 0 180)
					(length 3.81)
					(name "3V3"
						(effects
							(font
								(size 1.27 1.27)
							)
						)
					)
					(number "12"
						(effects
							(font
								(size 1.27 1.27)
							)
						)
					)
				)
				(pin passive line
					(at 30.48 0 180)
					(length 3.81)
					(hide yes)
					(name "3V3"
						(effects
							(font
								(size 1.27 1.27)
							)
						)
					)
					(number "14"
						(effects
							(font
								(size 1.27 1.27)
							)
						)
					)
				)
				(pin passive line
					(at 30.48 0 180)
					(length 3.81)
					(hide yes)
					(name "3V3"
						(effects
							(font
								(size 1.27 1.27)
							)
						)
					)
					(number "16"
						(effects
							(font
								(size 1.27 1.27)
							)
						)
					)
				)
				(pin passive line
					(at 30.48 0 180)
					(length 3.81)
					(hide yes)
					(name "3V3"
						(effects
							(font
								(size 1.27 1.27)
							)
						)
					)
					(number "18"
						(effects
							(font
								(size 1.27 1.27)
							)
						)
					)
				)
				(pin passive line
					(at 30.48 0 180)
					(length 3.81)
					(hide yes)
					(name "3V3"
						(effects
							(font
								(size 1.27 1.27)
							)
						)
					)
					(number "2"
						(effects
							(font
								(size 1.27 1.27)
							)
						)
					)
				)
				(pin passive line
					(at 30.48 0 180)
					(length 3.81)
					(hide yes)
					(name "3V3"
						(effects
							(font
								(size 1.27 1.27)
							)
						)
					)
					(number "4"
						(effects
							(font
								(size 1.27 1.27)
							)
						)
					)
				)
				(pin passive line
					(at 30.48 0 180)
					(length 3.81)
					(hide yes)
					(name "3V3"
						(effects
							(font
								(size 1.27 1.27)
							)
						)
					)
					(number "70"
						(effects
							(font
								(size 1.27 1.27)
							)
						)
					)
				)
				(pin passive line
					(at 30.48 0 180)
					(length 3.81)
					(hide yes)
					(name "3V3"
						(effects
							(font
								(size 1.27 1.27)
							)
						)
					)
					(number "72"
						(effects
							(font
								(size 1.27 1.27)
							)
						)
					)
				)
				(pin passive line
					(at 30.48 0 180)
					(length 3.81)
					(hide yes)
					(name "3V3"
						(effects
							(font
								(size 1.27 1.27)
							)
						)
					)
					(number "74"
						(effects
							(font
								(size 1.27 1.27)
							)
						)
					)
				)
				(pin input line
					(at 30.48 -12.7 180)
					(length 3.81)
					(name "SUSCLK"
						(effects
							(font
								(size 1.27 1.27)
							)
						)
					)
					(number "68"
						(effects
							(font
								(size 1.27 1.27)
							)
						)
					)
				)
				(pin output line
					(at 30.48 -26.67 180)
					(length 3.81)
					(name "ALERT"
						(effects
							(font
								(size 1.27 1.27)
							)
						)
					)
					(number "44"
						(effects
							(font
								(size 1.27 1.27)
							)
						)
					)
				)
				(pin bidirectional line
					(at 30.48 -29.21 180)
					(length 3.81)
					(name "SMB_DATA"
						(effects
							(font
								(size 1.27 1.27)
							)
						)
					)
					(number "42"
						(effects
							(font
								(size 1.27 1.27)
							)
						)
					)
				)
				(pin input line
					(at 30.48 -31.75 180)
					(length 3.81)
					(name "SMB_CLK"
						(effects
							(font
								(size 1.27 1.27)
							)
						)
					)
					(number "40"
						(effects
							(font
								(size 1.27 1.27)
							)
						)
					)
				)
				(pin passive line
					(at 30.48 -54.61 180)
					(length 3.81)
					(name "LED"
						(effects
							(font
								(size 1.27 1.27)
							)
						)
					)
					(number "10"
						(effects
							(font
								(size 1.27 1.27)
							)
						)
					)
				)
				(pin passive line
					(at 30.48 -74.93 180)
					(length 3.81)
					(name "MP"
						(effects
							(font
								(size 1.27 1.27)
							)
						)
					)
					(number "MP1"
						(effects
							(font
								(size 1.27 1.27)
							)
						)
					)
				)
				(pin passive line
					(at 30.48 -74.93 180)
					(length 3.81)
					(hide yes)
					(name "MP"
						(effects
							(font
								(size 1.27 1.27)
							)
						)
					)
					(number "MP2"
						(effects
							(font
								(size 1.27 1.27)
							)
						)
					)
				)
				(pin power_in line
					(at 30.48 -77.47 180)
					(length 3.81)
					(name "GND"
						(effects
							(font
								(size 1.27 1.27)
							)
						)
					)
					(number "1"
						(effects
							(font
								(size 1.27 1.27)
							)
						)
					)
				)
				(pin passive line
					(at 30.48 -77.47 180)
					(length 3.81)
					(hide yes)
					(name "GND"
						(effects
							(font
								(size 1.27 1.27)
							)
						)
					)
					(number "15"
						(effects
							(font
								(size 1.27 1.27)
							)
						)
					)
				)
				(pin passive line
					(at 30.48 -77.47 180)
					(length 3.81)
					(hide yes)
					(name "GND"
						(effects
							(font
								(size 1.27 1.27)
							)
						)
					)
					(number "21"
						(effects
							(font
								(size 1.27 1.27)
							)
						)
					)
				)
				(pin passive line
					(at 30.48 -77.47 180)
					(length 3.81)
					(hide yes)
					(name "GND"
						(effects
							(font
								(size 1.27 1.27)
							)
						)
					)
					(number "27"
						(effects
							(font
								(size 1.27 1.27)
							)
						)
					)
				)
				(pin passive line
					(at 30.48 -77.47 180)
					(length 3.81)
					(hide yes)
					(name "GND"
						(effects
							(font
								(size 1.27 1.27)
							)
						)
					)
					(number "3"
						(effects
							(font
								(size 1.27 1.27)
							)
						)
					)
				)
				(pin passive line
					(at 30.48 -77.47 180)
					(length 3.81)
					(hide yes)
					(name "GND"
						(effects
							(font
								(size 1.27 1.27)
							)
						)
					)
					(number "33"
						(effects
							(font
								(size 1.27 1.27)
							)
						)
					)
				)
				(pin passive line
					(at 30.48 -77.47 180)
					(length 3.81)
					(hide yes)
					(name "GND"
						(effects
							(font
								(size 1.27 1.27)
							)
						)
					)
					(number "39"
						(effects
							(font
								(size 1.27 1.27)
							)
						)
					)
				)
				(pin passive line
					(at 30.48 -77.47 180)
					(length 3.81)
					(hide yes)
					(name "GND"
						(effects
							(font
								(size 1.27 1.27)
							)
						)
					)
					(number "45"
						(effects
							(font
								(size 1.27 1.27)
							)
						)
					)
				)
				(pin passive line
					(at 30.48 -77.47 180)
					(length 3.81)
					(hide yes)
					(name "GND"
						(effects
							(font
								(size 1.27 1.27)
							)
						)
					)
					(number "51"
						(effects
							(font
								(size 1.27 1.27)
							)
						)
					)
				)
				(pin passive line
					(at 30.48 -77.47 180)
					(length 3.81)
					(hide yes)
					(name "GND"
						(effects
							(font
								(size 1.27 1.27)
							)
						)
					)
					(number "57"
						(effects
							(font
								(size 1.27 1.27)
							)
						)
					)
				)
				(pin passive line
					(at 30.48 -77.47 180)
					(length 3.81)
					(hide yes)
					(name "GND"
						(effects
							(font
								(size 1.27 1.27)
							)
						)
					)
					(number "71"
						(effects
							(font
								(size 1.27 1.27)
							)
						)
					)
				)
				(pin passive line
					(at 30.48 -77.47 180)
					(length 3.81)
					(hide yes)
					(name "GND"
						(effects
							(font
								(size 1.27 1.27)
							)
						)
					)
					(number "73"
						(effects
							(font
								(size 1.27 1.27)
							)
						)
					)
				)
				(pin passive line
					(at 30.48 -77.47 180)
					(length 3.81)
					(hide yes)
					(name "GND"
						(effects
							(font
								(size 1.27 1.27)
							)
						)
					)
					(number "75"
						(effects
							(font
								(size 1.27 1.27)
							)
						)
					)
				)
				(pin passive line
					(at 30.48 -77.47 180)
					(length 3.81)
					(hide yes)
					(name "GND"
						(effects
							(font
								(size 1.27 1.27)
							)
						)
					)
					(number "9"
						(effects
							(font
								(size 1.27 1.27)
							)
						)
					)
				)
			)
		)
	(symbol "antmicroPushbuttonSwitches:SW_KMR211NGLFS_SMD"
			(pin_names
				(hide yes)
			)
			(exclude_from_sim no)
			(in_bom yes)
			(on_board yes)
			(property "Reference" "SW"
				(at 25.4 -2.54 0)
				(effects
					(font
						(size 1.27 1.27)
						(thickness 0.15)
					)
					(justify left bottom)
				)
			)
			(property "Value" "SW_KMR211NGLFS_SMD"
				(at 25.4 -7.62 0)
				(effects
					(font
						(size 1.27 1.27)
						(thickness 0.15)
					)
					(justify left bottom)
					(hide yes)
				)
			)
			(property "Footprint" "antmicro-footprints:SW_KMR211NGLFS_SMD"
				(at 25.4 -10.16 0)
				(effects
					(font
						(size 1.27 1.27)
						(thickness 0.15)
					)
					(justify left bottom)
					(hide yes)
				)
			)
			(property "Datasheet" "http://www.farnell.com/datasheets/2631211.pdf"
				(at 25.4 -12.7 0)
				(effects
					(font
						(size 1.27 1.27)
						(thickness 0.15)
					)
					(justify left bottom)
					(hide yes)
				)
			)
			(property "Description" "Tactile Switch, KMR 2 Series, Top Actuated, Surface Mount, Oval Button, 120 gf, 50mA at 32VDC"
				(at 0 0 0)
				(effects
					(font
						(size 1.27 1.27)
					)
					(hide yes)
				)
			)
			(property "MPN" "KMR211NGLFS"
				(at 25.4 -5.08 0)
				(effects
					(font
						(size 1.27 1.27)
						(thickness 0.15)
					)
					(justify left bottom)
				)
			)
			(property "Manufacturer" "C&K"
				(at 25.4 -15.24 0)
				(effects
					(font
						(size 1.27 1.27)
						(thickness 0.15)
					)
					(justify left bottom)
					(hide yes)
				)
			)
			(property "Author" "Antmicro"
				(at 25.4 -17.78 0)
				(effects
					(font
						(size 1.27 1.27)
						(thickness 0.15)
					)
					(justify left bottom)
					(hide yes)
				)
			)
			(property "License" "Apache-2.0"
				(at 25.4 -20.32 0)
				(effects
					(font
						(size 1.27 1.27)
						(thickness 0.15)
					)
					(justify left bottom)
					(hide yes)
				)
			)
			(property "ki_keywords" "VERTICAL, SMT, SWITCH, MECHANICAL, TACTILE"
				(at 0 0 0)
				(effects
					(font
						(size 1.27 1.27)
					)
					(hide yes)
				)
			)
			(symbol "SW_KMR211NGLFS_SMD_1_1"
				(polyline
					(pts
						(xy 2.54 0) (xy 3.302 0)
					)
					(stroke
						(width 0.254)
						(type default)
					)
					(fill
						(type none)
					)
				)
				(polyline
					(pts
						(xy 2.54 -2.54) (xy 3.302 -2.54)
					)
					(stroke
						(width 0.254)
						(type default)
					)
					(fill
						(type none)
					)
				)
				(polyline
					(pts
						(xy 3.302 1.27) (xy 6.858 1.27)
					)
					(stroke
						(width 0.254)
						(type default)
					)
					(fill
						(type none)
					)
				)
				(circle
					(center 3.556 0)
					(radius 0.254)
					(stroke
						(width 0.254)
						(type default)
					)
					(fill
						(type none)
					)
				)
				(polyline
					(pts
						(xy 3.556 -0.3048) (xy 3.556 -2.1844)
					)
					(stroke
						(width 0.254)
						(type default)
					)
					(fill
						(type none)
					)
				)
				(circle
					(center 3.556 -2.54)
					(radius 0.254)
					(stroke
						(width 0.254)
						(type default)
					)
					(fill
						(type none)
					)
				)
				(polyline
					(pts
						(xy 4.064 2.794) (xy 6.096 2.794)
					)
					(stroke
						(width 0.254)
						(type default)
					)
					(fill
						(type none)
					)
				)
				(polyline
					(pts
						(xy 5.08 1.27) (xy 5.08 2.794)
					)
					(stroke
						(width 0.254)
						(type default)
					)
					(fill
						(type none)
					)
				)
				(circle
					(center 6.604 0)
					(radius 0.254)
					(stroke
						(width 0.254)
						(type default)
					)
					(fill
						(type none)
					)
				)
				(polyline
					(pts
						(xy 6.604 -0.254) (xy 6.604 -2.1844)
					)
					(stroke
						(width 0.254)
						(type default)
					)
					(fill
						(type none)
					)
				)
				(circle
					(center 6.604 -2.54)
					(radius 0.254)
					(stroke
						(width 0.254)
						(type default)
					)
					(fill
						(type none)
					)
				)
				(polyline
					(pts
						(xy 7.62 0) (xy 6.858 0)
					)
					(stroke
						(width 0.254)
						(type default)
					)
					(fill
						(type none)
					)
				)
				(polyline
					(pts
						(xy 7.62 -2.54) (xy 6.858 -2.54)
					)
					(stroke
						(width 0.254)
						(type default)
					)
					(fill
						(type none)
					)
				)
				(pin passive line
					(at 0 0 0)
					(length 2.54)
					(name "1"
						(effects
							(font
								(size 1.27 1.27)
							)
						)
					)
					(number "1"
						(effects
							(font
								(size 1.27 1.27)
							)
						)
					)
				)
				(pin passive line
					(at 0 -2.54 0)
					(length 2.54)
					(name "2"
						(effects
							(font
								(size 1.27 1.27)
							)
						)
					)
					(number "2"
						(effects
							(font
								(size 1.27 1.27)
							)
						)
					)
				)
				(pin passive line
					(at 10.16 0 180)
					(length 2.54)
					(name "3"
						(effects
							(font
								(size 1.27 1.27)
							)
						)
					)
					(number "3"
						(effects
							(font
								(size 1.27 1.27)
							)
						)
					)
				)
				(pin passive line
					(at 10.16 -2.54 180)
					(length 2.54)
					(name "4"
						(effects
							(font
								(size 1.27 1.27)
							)
						)
					)
					(number "4"
						(effects
							(font
								(size 1.27 1.27)
							)
						)
					)
				)
			)
		)
	(symbol "antmicroRFTransceiverICs:PN7160A1_VFQFN"
			(exclude_from_sim no)
			(in_bom yes)
			(on_board yes)
			(property "Reference" "U"
				(at 44.45 0 0)
				(effects
					(font
						(size 1.27 1.27)
						(thickness 0.15)
					)
					(justify left bottom)
				)
			)
			(property "Value" "PN7160A1_VFQFN"
				(at 44.45 -5.08 0)
				(effects
					(font
						(size 1.27 1.27)
						(thickness 0.15)
					)
					(justify left bottom)
					(hide yes)
				)
			)
			(property "Footprint" "antmicro-footprints:VFQFN-40-1EP_6x6mm"
				(at 44.45 -7.62 0)
				(effects
					(font
						(size 1.27 1.27)
						(thickness 0.15)
					)
					(justify left bottom)
					(hide yes)
				)
			)
			(property "Datasheet" "https://www.nxp.com/docs/en/data-sheet/PN7160_PN7161.pdf"
				(at 44.45 -10.16 0)
				(effects
					(font
						(size 1.27 1.27)
						(thickness 0.15)
					)
					(justify left bottom)
					(hide yes)
				)
			)
			(property "Description" "Near Field Communication (NFC) controller"
				(at 0 0 0)
				(effects
					(font
						(size 1.27 1.27)
					)
					(hide yes)
				)
			)
			(property "MPN" "PN7160A1HN/C100E"
				(at 44.45 -2.54 0)
				(effects
					(font
						(size 1.27 1.27)
						(thickness 0.15)
					)
					(justify left bottom)
				)
			)
			(property "Manufacturer" "NXP"
				(at 44.45 -12.7 0)
				(effects
					(font
						(size 1.27 1.27)
						(thickness 0.15)
					)
					(justify left bottom)
					(hide yes)
				)
			)
			(property "Author" "Antmicro"
				(at 44.45 -15.24 0)
				(effects
					(font
						(size 1.27 1.27)
						(thickness 0.15)
					)
					(justify left bottom)
					(hide yes)
				)
			)
			(property "License" "Apache-2.0"
				(at 44.45 -17.78 0)
				(effects
					(font
						(size 1.27 1.27)
						(thickness 0.15)
					)
					(justify left bottom)
					(hide yes)
				)
			)
			(property "ki_keywords" "NFC, IC, RF, I2C"
				(at 0 0 0)
				(effects
					(font
						(size 1.27 1.27)
					)
					(hide yes)
				)
			)
			(property "ki_fp_filters" "QFN40_PN7160_NXP QFN40_PN7160_NXP-M QFN40_PN7160_NXP-L"
				(at 0 0 0)
				(effects
					(font
						(size 1.27 1.27)
					)
					(hide yes)
				)
			)
			(symbol "PN7160A1_VFQFN_1_1"
				(rectangle
					(start 2.54 2.54)
					(end 27.94 -63.5)
					(stroke
						(width 0.254)
						(type default)
					)
					(fill
						(type background)
					)
				)
				(pin power_in line
					(at 0 0 0)
					(length 2.54)
					(name "V_{DD(PAD)}"
						(effects
							(font
								(size 1.27 1.27)
							)
						)
					)
					(number "6"
						(effects
							(font
								(size 1.27 1.27)
							)
						)
					)
				)
				(pin power_in line
					(at 0 -2.54 0)
					(length 2.54)
					(name "V_{DD(UP)}"
						(effects
							(font
								(size 1.27 1.27)
							)
						)
					)
					(number "13"
						(effects
							(font
								(size 1.27 1.27)
							)
						)
					)
				)
				(pin passive line
					(at 0 -5.08 0)
					(length 2.54)
					(hide yes)
					(name "V_{BAT}"
						(effects
							(font
								(size 1.27 1.27)
							)
						)
					)
					(number "12"
						(effects
							(font
								(size 1.27 1.27)
							)
						)
					)
				)
				(pin power_in line
					(at 0 -5.08 0)
					(length 2.54)
					(name "V_{BAT}"
						(effects
							(font
								(size 1.27 1.27)
							)
						)
					)
					(number "28"
						(effects
							(font
								(size 1.27 1.27)
							)
						)
					)
				)
				(pin input line
					(at 0 -8.89 0)
					(length 2.54)
					(name "VEN/~{RST}"
						(effects
							(font
								(size 1.27 1.27)
							)
						)
					)
					(number "10"
						(effects
							(font
								(size 1.27 1.27)
							)
						)
					)
				)
				(pin output line
					(at 0 -11.43 0)
					(length 2.54)
					(name "DCDC_EN"
						(effects
							(font
								(size 1.27 1.27)
							)
						)
					)
					(number "37"
						(effects
							(font
								(size 1.27 1.27)
							)
						)
					)
				)
				(pin input line
					(at 0 -13.97 0)
					(length 2.54)
					(name "WKUP_REQ"
						(effects
							(font
								(size 1.27 1.27)
							)
						)
					)
					(number "39"
						(effects
							(font
								(size 1.27 1.27)
							)
						)
					)
				)
				(pin output line
					(at 0 -16.51 0)
					(length 2.54)
					(name "CLK_REQ"
						(effects
							(font
								(size 1.27 1.27)
							)
						)
					)
					(number "40"
						(effects
							(font
								(size 1.27 1.27)
							)
						)
					)
				)
				(pin output line
					(at 0 -19.05 0)
					(length 2.54)
					(name "IRQ"
						(effects
							(font
								(size 1.27 1.27)
							)
						)
					)
					(number "8"
						(effects
							(font
								(size 1.27 1.27)
							)
						)
					)
				)
				(pin power_in line
					(at 0 -21.59 0)
					(length 2.54)
					(name "V_{DD(HF)}"
						(effects
							(font
								(size 1.27 1.27)
							)
						)
					)
					(number "25"
						(effects
							(font
								(size 1.27 1.27)
							)
						)
					)
				)
				(pin bidirectional line
					(at 0 -25.4 0)
					(length 2.54)
					(name "I2C_SCL"
						(effects
							(font
								(size 1.27 1.27)
							)
						)
					)
					(number "7"
						(effects
							(font
								(size 1.27 1.27)
							)
						)
					)
				)
				(pin bidirectional line
					(at 0 -27.94 0)
					(length 2.54)
					(name "I2C_SDA"
						(effects
							(font
								(size 1.27 1.27)
							)
						)
					)
					(number "5"
						(effects
							(font
								(size 1.27 1.27)
							)
						)
					)
				)
				(pin bidirectional line
					(at 0 -30.48 0)
					(length 2.54)
					(name "I2C_ADR0"
						(effects
							(font
								(size 1.27 1.27)
							)
						)
					)
					(number "1"
						(effects
							(font
								(size 1.27 1.27)
							)
						)
					)
				)
				(pin bidirectional line
					(at 0 -33.02 0)
					(length 2.54)
					(name "I2C_ADR1"
						(effects
							(font
								(size 1.27 1.27)
							)
						)
					)
					(number "3"
						(effects
							(font
								(size 1.27 1.27)
							)
						)
					)
				)
				(pin input line
					(at 0 -35.56 0)
					(length 2.54)
					(name "DWL_REQ"
						(effects
							(font
								(size 1.27 1.27)
							)
						)
					)
					(number "2"
						(effects
							(font
								(size 1.27 1.27)
							)
						)
					)
				)
				(pin power_in line
					(at 0 -39.37 0)
					(length 2.54)
					(name "V_{DD(A)}"
						(effects
							(font
								(size 1.27 1.27)
							)
						)
					)
					(number "26"
						(effects
							(font
								(size 1.27 1.27)
							)
						)
					)
				)
				(pin power_in line
					(at 0 -41.91 0)
					(length 2.54)
					(name "V_{DD(D)}"
						(effects
							(font
								(size 1.27 1.27)
							)
						)
					)
					(number "31"
						(effects
							(font
								(size 1.27 1.27)
							)
						)
					)
				)
				(pin power_in line
					(at 0 -44.45 0)
					(length 2.54)
					(name "V_{DD}"
						(effects
							(font
								(size 1.27 1.27)
							)
						)
					)
					(number "27"
						(effects
							(font
								(size 1.27 1.27)
							)
						)
					)
				)
				(pin power_in line
					(at 0 -48.26 0)
					(length 2.54)
					(name "V_{DD(TX)}"
						(effects
							(font
								(size 1.27 1.27)
							)
						)
					)
					(number "14"
						(effects
							(font
								(size 1.27 1.27)
							)
						)
					)
				)
				(pin power_in line
					(at 0 -50.8 0)
					(length 2.54)
					(name "TVDD_IN"
						(effects
							(font
								(size 1.27 1.27)
							)
						)
					)
					(number "18"
						(effects
							(font
								(size 1.27 1.27)
							)
						)
					)
				)
				(pin power_in line
					(at 0 -53.34 0)
					(length 2.54)
					(name "TVDD_IN2"
						(effects
							(font
								(size 1.27 1.27)
							)
						)
					)
					(number "22"
						(effects
							(font
								(size 1.27 1.27)
							)
						)
					)
				)
				(pin power_in line
					(at 0 -57.15 0)
					(length 2.54)
					(name "V_{DD(VMID)}"
						(effects
							(font
								(size 1.27 1.27)
							)
						)
					)
					(number "17"
						(effects
							(font
								(size 1.27 1.27)
							)
						)
					)
				)
				(pin power_out line
					(at 0 -60.96 0)
					(length 2.54)
					(hide yes)
					(name "VSS"
						(effects
							(font
								(size 1.27 1.27)
							)
						)
					)
					(number "20"
						(effects
							(font
								(size 1.27 1.27)
							)
						)
					)
				)
				(pin power_out line
					(at 0 -60.96 0)
					(length 2.54)
					(hide yes)
					(name "VSS"
						(effects
							(font
								(size 1.27 1.27)
							)
						)
					)
					(number "4"
						(effects
							(font
								(size 1.27 1.27)
							)
						)
					)
				)
				(pin passive line
					(at 0 -60.96 0)
					(length 2.54)
					(name "VSS"
						(effects
							(font
								(size 1.27 1.27)
							)
						)
					)
					(number "41"
						(effects
							(font
								(size 1.27 1.27)
							)
						)
					)
				)
				(pin power_out line
					(at 0 -60.96 0)
					(length 2.54)
					(hide yes)
					(name "VSS"
						(effects
							(font
								(size 1.27 1.27)
							)
						)
					)
					(number "9"
						(effects
							(font
								(size 1.27 1.27)
							)
						)
					)
				)
				(pin no_connect line
					(at 27.94 -19.05 180)
					(length 2.54)
					(hide yes)
					(name "IC"
						(effects
							(font
								(size 1.27 1.27)
							)
						)
					)
					(number "38"
						(effects
							(font
								(size 1.27 1.27)
							)
						)
					)
				)
				(pin no_connect line
					(at 27.94 -20.32 180)
					(length 2.54)
					(hide yes)
					(name "IC"
						(effects
							(font
								(size 1.27 1.27)
							)
						)
					)
					(number "11"
						(effects
							(font
								(size 1.27 1.27)
							)
						)
					)
				)
				(pin no_connect line
					(at 27.94 -21.59 180)
					(length 2.54)
					(hide yes)
					(name "NC"
						(effects
							(font
								(size 1.27 1.27)
							)
						)
					)
					(number "32"
						(effects
							(font
								(size 1.27 1.27)
							)
						)
					)
				)
				(pin no_connect line
					(at 27.94 -22.86 180)
					(length 2.54)
					(hide yes)
					(name "NC"
						(effects
							(font
								(size 1.27 1.27)
							)
						)
					)
					(number "33"
						(effects
							(font
								(size 1.27 1.27)
							)
						)
					)
				)
				(pin no_connect line
					(at 27.94 -24.13 180)
					(length 2.54)
					(hide yes)
					(name "NC"
						(effects
							(font
								(size 1.27 1.27)
							)
						)
					)
					(number "34"
						(effects
							(font
								(size 1.27 1.27)
							)
						)
					)
				)
				(pin no_connect line
					(at 27.94 -25.4 180)
					(length 2.54)
					(hide yes)
					(name "NC"
						(effects
							(font
								(size 1.27 1.27)
							)
						)
					)
					(number "35"
						(effects
							(font
								(size 1.27 1.27)
							)
						)
					)
				)
				(pin no_connect line
					(at 27.94 -26.67 180)
					(length 2.54)
					(hide yes)
					(name "NC"
						(effects
							(font
								(size 1.27 1.27)
							)
						)
					)
					(number "36"
						(effects
							(font
								(size 1.27 1.27)
							)
						)
					)
				)
				(pin bidirectional line
					(at 30.48 0 180)
					(length 2.54)
					(name "ANT1"
						(effects
							(font
								(size 1.27 1.27)
							)
						)
					)
					(number "23"
						(effects
							(font
								(size 1.27 1.27)
							)
						)
					)
				)
				(pin input line
					(at 30.48 -7.62 180)
					(length 2.54)
					(name "RXP"
						(effects
							(font
								(size 1.27 1.27)
							)
						)
					)
					(number "16"
						(effects
							(font
								(size 1.27 1.27)
							)
						)
					)
				)
				(pin output line
					(at 30.48 -15.24 180)
					(length 2.54)
					(name "TX1"
						(effects
							(font
								(size 1.27 1.27)
							)
						)
					)
					(number "21"
						(effects
							(font
								(size 1.27 1.27)
							)
						)
					)
				)
				(pin output line
					(at 30.48 -30.48 180)
					(length 2.54)
					(name "TX2"
						(effects
							(font
								(size 1.27 1.27)
							)
						)
					)
					(number "19"
						(effects
							(font
								(size 1.27 1.27)
							)
						)
					)
				)
				(pin input line
					(at 30.48 -38.1 180)
					(length 2.54)
					(name "RXN"
						(effects
							(font
								(size 1.27 1.27)
							)
						)
					)
					(number "15"
						(effects
							(font
								(size 1.27 1.27)
							)
						)
					)
				)
				(pin bidirectional line
					(at 30.48 -45.72 180)
					(length 2.54)
					(name "ANT2"
						(effects
							(font
								(size 1.27 1.27)
							)
						)
					)
					(number "24"
						(effects
							(font
								(size 1.27 1.27)
							)
						)
					)
				)
				(pin input line
					(at 30.48 -58.42 180)
					(length 2.54)
					(name "CLK_XTAL1"
						(effects
							(font
								(size 1.27 1.27)
							)
						)
					)
					(number "30"
						(effects
							(font
								(size 1.27 1.27)
							)
						)
					)
				)
				(pin output line
					(at 30.48 -60.96 180)
					(length 2.54)
					(name "XTAL2"
						(effects
							(font
								(size 1.27 1.27)
							)
						)
					)
					(number "29"
						(effects
							(font
								(size 1.27 1.27)
							)
						)
					)
				)
			)
		)
	(symbol "antmicroResistorNetworksArrays:R_4x100R_0402_array"
			(pin_names
				(hide yes)
			)
			(exclude_from_sim no)
			(in_bom yes)
			(on_board yes)
			(property "Reference" "R"
				(at 26.67 -2.54 0)
				(effects
					(font
						(size 1.27 1.27)
						(thickness 0.15)
					)
					(justify left bottom)
				)
			)
			(property "Value" "R_4x100R_0402_array"
				(at 26.67 -5.08 0)
				(effects
					(font
						(size 1.27 1.27)
						(thickness 0.15)
					)
					(justify left bottom)
					(hide yes)
				)
			)
			(property "Footprint" "antmicro-footprints:R_Array_4x0402_Panasonic_EXB28V"
				(at 26.67 -10.16 0)
				(effects
					(font
						(size 1.27 1.27)
						(thickness 0.15)
					)
					(justify left bottom)
					(hide yes)
				)
			)
			(property "Datasheet" "http://industrial.panasonic.com/cdbs/www-data/pdf/AOC0000/AOC0000C14.pdf"
				(at 26.67 -12.7 0)
				(effects
					(font
						(size 1.27 1.27)
						(thickness 0.15)
					)
					(justify left bottom)
					(hide yes)
				)
			)
			(property "Description" "Fixed Network Resistor, 100 ohm, Isolated, 4 Resistors, 0804 [2010 Metric], Convex, ± 5%"
				(at 0 0 0)
				(effects
					(font
						(size 1.27 1.27)
					)
					(hide yes)
				)
			)
			(property "MPN" "EXB-28V101JX"
				(at 26.67 -15.24 0)
				(effects
					(font
						(size 1.27 1.27)
						(thickness 0.15)
					)
					(justify left bottom)
					(hide yes)
				)
			)
			(property "Manufacturer" "Panasonic"
				(at 26.67 -17.78 0)
				(effects
					(font
						(size 1.27 1.27)
						(thickness 0.15)
					)
					(justify left bottom)
					(hide yes)
				)
			)
			(property "Author" "Antmicro"
				(at 26.67 -20.32 0)
				(effects
					(font
						(size 1.27 1.27)
						(thickness 0.15)
					)
					(justify left bottom)
					(hide yes)
				)
			)
			(property "License" "Apache-2.0"
				(at 26.67 -22.86 0)
				(effects
					(font
						(size 1.27 1.27)
						(thickness 0.15)
					)
					(justify left bottom)
					(hide yes)
				)
			)
			(property "Val" "R_4x100R_0402"
				(at 26.67 -7.62 0)
				(effects
					(font
						(size 1.27 1.27)
					)
					(justify left bottom)
				)
			)
			(property "ki_keywords" "0402, SMT, RESISTOR, PASSIVE"
				(at 0 0 0)
				(effects
					(font
						(size 1.27 1.27)
					)
					(hide yes)
				)
			)
			(symbol "R_4x100R_0402_array_0_1"
				(polyline
					(pts
						(xy 2.54 0) (xy 3.175 0)
					)
					(stroke
						(width 0)
						(type default)
					)
					(fill
						(type none)
					)
				)
				(polyline
					(pts
						(xy 2.54 -2.54) (xy 3.175 -2.54)
					)
					(stroke
						(width 0)
						(type default)
					)
					(fill
						(type none)
					)
				)
				(polyline
					(pts
						(xy 2.54 -5.08) (xy 3.175 -5.08)
					)
					(stroke
						(width 0)
						(type default)
					)
					(fill
						(type none)
					)
				)
				(polyline
					(pts
						(xy 2.54 -7.62) (xy 3.175 -7.62)
					)
					(stroke
						(width 0)
						(type default)
					)
					(fill
						(type none)
					)
				)
				(rectangle
					(start 2.667 1.27)
					(end 7.493 -8.89)
					(stroke
						(width 0.254)
						(type default)
					)
					(fill
						(type background)
					)
				)
				(rectangle
					(start 6.985 0.635)
					(end 3.175 -0.635)
					(stroke
						(width 0.254)
						(type default)
					)
					(fill
						(type none)
					)
				)
				(polyline
					(pts
						(xy 6.985 0) (xy 7.62 0)
					)
					(stroke
						(width 0)
						(type default)
					)
					(fill
						(type none)
					)
				)
				(rectangle
					(start 6.985 -1.905)
					(end 3.175 -3.175)
					(stroke
						(width 0.254)
						(type default)
					)
					(fill
						(type none)
					)
				)
				(polyline
					(pts
						(xy 6.985 -2.54) (xy 7.62 -2.54)
					)
					(stroke
						(width 0)
						(type default)
					)
					(fill
						(type none)
					)
				)
				(rectangle
					(start 6.985 -4.445)
					(end 3.175 -5.715)
					(stroke
						(width 0.254)
						(type default)
					)
					(fill
						(type none)
					)
				)
				(polyline
					(pts
						(xy 6.985 -5.08) (xy 7.62 -5.08)
					)
					(stroke
						(width 0)
						(type default)
					)
					(fill
						(type none)
					)
				)
				(rectangle
					(start 6.985 -6.985)
					(end 3.175 -8.255)
					(stroke
						(width 0.254)
						(type default)
					)
					(fill
						(type none)
					)
				)
				(polyline
					(pts
						(xy 6.985 -7.62) (xy 7.62 -7.62)
					)
					(stroke
						(width 0)
						(type default)
					)
					(fill
						(type none)
					)
				)
			)
			(symbol "R_4x100R_0402_array_1_1"
				(pin passive line
					(at 0 0 0)
					(length 2.54)
					(name "R1.1"
						(effects
							(font
								(size 1.27 1.27)
							)
						)
					)
					(number "1"
						(effects
							(font
								(size 1.27 1.27)
							)
						)
					)
				)
				(pin passive line
					(at 0 -2.54 0)
					(length 2.54)
					(name "R2.1"
						(effects
							(font
								(size 1.27 1.27)
							)
						)
					)
					(number "2"
						(effects
							(font
								(size 1.27 1.27)
							)
						)
					)
				)
				(pin passive line
					(at 0 -5.08 0)
					(length 2.54)
					(name "R3.1"
						(effects
							(font
								(size 1.27 1.27)
							)
						)
					)
					(number "3"
						(effects
							(font
								(size 1.27 1.27)
							)
						)
					)
				)
				(pin passive line
					(at 0 -7.62 0)
					(length 2.54)
					(name "R4.1"
						(effects
							(font
								(size 1.27 1.27)
							)
						)
					)
					(number "4"
						(effects
							(font
								(size 1.27 1.27)
							)
						)
					)
				)
				(pin passive line
					(at 10.16 0 180)
					(length 2.54)
					(name "R1.2"
						(effects
							(font
								(size 1.27 1.27)
							)
						)
					)
					(number "8"
						(effects
							(font
								(size 1.27 1.27)
							)
						)
					)
				)
				(pin passive line
					(at 10.16 -2.54 180)
					(length 2.54)
					(name "R2.2"
						(effects
							(font
								(size 1.27 1.27)
							)
						)
					)
					(number "7"
						(effects
							(font
								(size 1.27 1.27)
							)
						)
					)
				)
				(pin passive line
					(at 10.16 -5.08 180)
					(length 2.54)
					(name "R3.2"
						(effects
							(font
								(size 1.27 1.27)
							)
						)
					)
					(number "6"
						(effects
							(font
								(size 1.27 1.27)
							)
						)
					)
				)
				(pin passive line
					(at 10.16 -7.62 180)
					(length 2.54)
					(name "R4.2"
						(effects
							(font
								(size 1.27 1.27)
							)
						)
					)
					(number "5"
						(effects
							(font
								(size 1.27 1.27)
							)
						)
					)
				)
			)
		)
	(symbol "antmicroResistors0402:R_0R_0402"
			(pin_numbers
				(hide yes)
			)
			(pin_names
				(hide yes)
			)
			(exclude_from_sim no)
			(in_bom yes)
			(on_board yes)
			(property "Reference" "R"
				(at 20.32 -5.08 0)
				(effects
					(font
						(size 1.27 1.27)
						(thickness 0.15)
					)
					(justify left bottom)
				)
			)
			(property "Value" "R_0R_0402"
				(at 20.32 -12.7 0)
				(effects
					(font
						(size 1.27 1.27)
						(thickness 0.15)
					)
					(justify left bottom)
					(hide yes)
				)
			)
			(property "Footprint" "antmicro-footprints:R_0402_1005Metric"
				(at 20.32 -15.24 0)
				(effects
					(font
						(size 1.27 1.27)
						(thickness 0.15)
					)
					(justify left bottom)
					(hide yes)
				)
			)
			(property "Datasheet" "https://industrial.panasonic.com/cdbs/www-data/pdf/RDA0000/AOA0000C301.pdf"
				(at 20.32 -17.78 0)
				(effects
					(font
						(size 1.27 1.27)
						(thickness 0.15)
					)
					(justify left bottom)
					(hide yes)
				)
			)
			(property "Description" "SMD Chip Resistor, Jumper, 0 ohm, 100 mW, 0402 [1005 Metric], Thick Film, General Purpose"
				(at 0 0 0)
				(effects
					(font
						(size 1.27 1.27)
					)
					(hide yes)
				)
			)
			(property "MPN" "ERJ2GE0R00X"
				(at 20.32 -20.32 0)
				(effects
					(font
						(size 1.27 1.27)
						(thickness 0.15)
					)
					(justify left bottom)
					(hide yes)
				)
			)
			(property "Manufacturer" "Panasonic"
				(at 20.32 -22.86 0)
				(effects
					(font
						(size 1.27 1.27)
						(thickness 0.15)
					)
					(justify left bottom)
					(hide yes)
				)
			)
			(property "License" "Apache-2.0"
				(at 20.32 -25.4 0)
				(effects
					(font
						(size 1.27 1.27)
						(thickness 0.15)
					)
					(justify left bottom)
					(hide yes)
				)
			)
			(property "Author" "Antmicro"
				(at 20.32 -27.94 0)
				(effects
					(font
						(size 1.27 1.27)
						(thickness 0.15)
					)
					(justify left bottom)
					(hide yes)
				)
			)
			(property "Val" "0R"
				(at 20.32 -7.62 0)
				(effects
					(font
						(size 1.27 1.27)
						(thickness 0.15)
					)
					(justify left bottom)
				)
			)
			(property "Tolerance" "~"
				(at 20.32 -10.16 0)
				(effects
					(font
						(size 1.27 1.27)
					)
					(justify left bottom)
					(hide yes)
				)
			)
			(property "Current" "1A"
				(at 20.32 -30.48 0)
				(effects
					(font
						(size 1.27 1.27)
						(thickness 0.15)
					)
					(justify left bottom)
					(hide yes)
				)
			)
			(property "ki_keywords" "0402, SMT, RESISTOR, PASSIVE"
				(at 0 0 0)
				(effects
					(font
						(size 1.27 1.27)
					)
					(hide yes)
				)
			)
			(symbol "R_0R_0402_0_1"
				(rectangle
					(start 0.635 0.889)
					(end 4.445 -0.889)
					(stroke
						(width 0.254)
						(type default)
					)
					(fill
						(type none)
					)
				)
			)
			(symbol "R_0R_0402_1_1"
				(pin passive line
					(at 0 0 0)
					(length 0.635)
					(name "~"
						(effects
							(font
								(size 1.27 1.27)
							)
						)
					)
					(number "1"
						(effects
							(font
								(size 1.27 1.27)
							)
						)
					)
				)
				(pin passive line
					(at 5.08 0 180)
					(length 0.635)
					(name "~"
						(effects
							(font
								(size 1.27 1.27)
							)
						)
					)
					(number "2"
						(effects
							(font
								(size 1.27 1.27)
							)
						)
					)
				)
			)
		)
	(symbol "antmicroResistors0402:R_100k_0402"
			(pin_numbers
				(hide yes)
			)
			(pin_names
				(hide yes)
			)
			(exclude_from_sim no)
			(in_bom yes)
			(on_board yes)
			(property "Reference" "R"
				(at 20.32 -5.08 0)
				(effects
					(font
						(size 1.27 1.27)
						(thickness 0.15)
					)
					(justify left bottom)
				)
			)
			(property "Value" "R_100k_0402"
				(at 20.32 -12.7 0)
				(effects
					(font
						(size 1.27 1.27)
						(thickness 0.15)
					)
					(justify left bottom)
					(hide yes)
				)
			)
			(property "Footprint" "antmicro-footprints:R_0402_1005Metric"
				(at 20.32 -15.24 0)
				(effects
					(font
						(size 1.27 1.27)
						(thickness 0.15)
					)
					(justify left bottom)
					(hide yes)
				)
			)
			(property "Datasheet" "https://www.bourns.com/docs/product-datasheets/cr.pdf"
				(at 20.32 -17.78 0)
				(effects
					(font
						(size 1.27 1.27)
						(thickness 0.15)
					)
					(justify left bottom)
					(hide yes)
				)
			)
			(property "Description" "SMD Chip Resistor, 100 kohm, ± 1%, 62.5 mW, 0402 [1005 Metric], Thick Film, General Purpose"
				(at 0 0 0)
				(effects
					(font
						(size 1.27 1.27)
					)
					(hide yes)
				)
			)
			(property "MPN" "CR0402-FX-1003GLF"
				(at 20.32 -20.32 0)
				(effects
					(font
						(size 1.27 1.27)
						(thickness 0.15)
					)
					(justify left bottom)
					(hide yes)
				)
			)
			(property "Manufacturer" "Bourns"
				(at 20.32 -22.86 0)
				(effects
					(font
						(size 1.27 1.27)
						(thickness 0.15)
					)
					(justify left bottom)
					(hide yes)
				)
			)
			(property "License" "Apache-2.0"
				(at 20.32 -25.4 0)
				(effects
					(font
						(size 1.27 1.27)
						(thickness 0.15)
					)
					(justify left bottom)
					(hide yes)
				)
			)
			(property "Author" "Antmicro"
				(at 20.32 -27.94 0)
				(effects
					(font
						(size 1.27 1.27)
						(thickness 0.15)
					)
					(justify left bottom)
					(hide yes)
				)
			)
			(property "Val" "100k"
				(at 20.32 -7.62 0)
				(effects
					(font
						(size 1.27 1.27)
						(thickness 0.15)
					)
					(justify left bottom)
				)
			)
			(property "Tolerance" "1%"
				(at 20.32 -10.16 0)
				(effects
					(font
						(size 1.27 1.27)
					)
					(justify left bottom)
					(hide yes)
				)
			)
			(property "ki_keywords" "0402, SMT, RESISTOR, PASSIVE"
				(at 0 0 0)
				(effects
					(font
						(size 1.27 1.27)
					)
					(hide yes)
				)
			)
			(symbol "R_100k_0402_0_1"
				(rectangle
					(start 0.635 0.889)
					(end 4.445 -0.889)
					(stroke
						(width 0.254)
						(type default)
					)
					(fill
						(type none)
					)
				)
			)
			(symbol "R_100k_0402_1_1"
				(pin passive line
					(at 0 0 0)
					(length 0.635)
					(name "~"
						(effects
							(font
								(size 1.27 1.27)
							)
						)
					)
					(number "1"
						(effects
							(font
								(size 1.27 1.27)
							)
						)
					)
				)
				(pin passive line
					(at 5.08 0 180)
					(length 0.635)
					(name "~"
						(effects
							(font
								(size 1.27 1.27)
							)
						)
					)
					(number "2"
						(effects
							(font
								(size 1.27 1.27)
							)
						)
					)
				)
			)
		)
	(symbol "antmicroResistors0402:R_10k_0402"
			(pin_numbers
				(hide yes)
			)
			(pin_names
				(hide yes)
			)
			(exclude_from_sim no)
			(in_bom yes)
			(on_board yes)
			(property "Reference" "R"
				(at 20.32 -5.08 0)
				(effects
					(font
						(size 1.27 1.27)
						(thickness 0.15)
					)
					(justify left bottom)
				)
			)
			(property "Value" "R_10k_0402"
				(at 20.32 -12.7 0)
				(effects
					(font
						(size 1.27 1.27)
						(thickness 0.15)
					)
					(justify left bottom)
					(hide yes)
				)
			)
			(property "Footprint" "antmicro-footprints:R_0402_1005Metric"
				(at 20.32 -15.24 0)
				(effects
					(font
						(size 1.27 1.27)
						(thickness 0.15)
					)
					(justify left bottom)
					(hide yes)
				)
			)
			(property "Datasheet" "https://www.bourns.com/docs/product-datasheets/cr.pdf"
				(at 20.32 -17.78 0)
				(effects
					(font
						(size 1.27 1.27)
						(thickness 0.15)
					)
					(justify left bottom)
					(hide yes)
				)
			)
			(property "Description" "SMD Chip Resistor, 10 kohm, ± 1%, 62.5 mW, 0402 [1005 Metric], Thick Film, General Purpose"
				(at 0 0 0)
				(effects
					(font
						(size 1.27 1.27)
					)
					(hide yes)
				)
			)
			(property "MPN" "CR0402-FX-1002GLF"
				(at 20.32 -20.32 0)
				(effects
					(font
						(size 1.27 1.27)
						(thickness 0.15)
					)
					(justify left bottom)
					(hide yes)
				)
			)
			(property "Manufacturer" "Bourns"
				(at 20.32 -22.86 0)
				(effects
					(font
						(size 1.27 1.27)
						(thickness 0.15)
					)
					(justify left bottom)
					(hide yes)
				)
			)
			(property "License" "Apache-2.0"
				(at 20.32 -25.4 0)
				(effects
					(font
						(size 1.27 1.27)
						(thickness 0.15)
					)
					(justify left bottom)
					(hide yes)
				)
			)
			(property "Author" "Antmicro"
				(at 20.32 -27.94 0)
				(effects
					(font
						(size 1.27 1.27)
						(thickness 0.15)
					)
					(justify left bottom)
					(hide yes)
				)
			)
			(property "Val" "10k"
				(at 20.32 -7.62 0)
				(effects
					(font
						(size 1.27 1.27)
						(thickness 0.15)
					)
					(justify left bottom)
				)
			)
			(property "Tolerance" "1%"
				(at 20.32 -10.16 0)
				(effects
					(font
						(size 1.27 1.27)
					)
					(justify left bottom)
					(hide yes)
				)
			)
			(property "ki_keywords" "0402, SMT, RESISTOR, PASSIVE"
				(at 0 0 0)
				(effects
					(font
						(size 1.27 1.27)
					)
					(hide yes)
				)
			)
			(symbol "R_10k_0402_0_1"
				(rectangle
					(start 0.635 0.889)
					(end 4.445 -0.889)
					(stroke
						(width 0.254)
						(type default)
					)
					(fill
						(type none)
					)
				)
			)
			(symbol "R_10k_0402_1_1"
				(pin passive line
					(at 0 0 0)
					(length 0.635)
					(name "~"
						(effects
							(font
								(size 1.27 1.27)
							)
						)
					)
					(number "1"
						(effects
							(font
								(size 1.27 1.27)
							)
						)
					)
				)
				(pin passive line
					(at 5.08 0 180)
					(length 0.635)
					(name "~"
						(effects
							(font
								(size 1.27 1.27)
							)
						)
					)
					(number "2"
						(effects
							(font
								(size 1.27 1.27)
							)
						)
					)
				)
			)
		)
	(symbol "antmicroResistors0402:R_12k_0402"
			(pin_numbers
				(hide yes)
			)
			(pin_names
				(hide yes)
			)
			(exclude_from_sim no)
			(in_bom yes)
			(on_board yes)
			(property "Reference" "R"
				(at 20.32 -5.08 0)
				(effects
					(font
						(size 1.27 1.27)
						(thickness 0.15)
					)
					(justify left bottom)
				)
			)
			(property "Value" "R_12k_0402"
				(at 20.32 -12.7 0)
				(effects
					(font
						(size 1.27 1.27)
						(thickness 0.15)
					)
					(justify left bottom)
					(hide yes)
				)
			)
			(property "Footprint" "antmicro-footprints:R_0402_1005Metric"
				(at 20.32 -15.24 0)
				(effects
					(font
						(size 1.27 1.27)
						(thickness 0.15)
					)
					(justify left bottom)
					(hide yes)
				)
			)
			(property "Datasheet" "https://www.bourns.com/docs/product-datasheets/cr.pdf"
				(at 20.32 -17.78 0)
				(effects
					(font
						(size 1.27 1.27)
						(thickness 0.15)
					)
					(justify left bottom)
					(hide yes)
				)
			)
			(property "Description" "SMD Chip Resistor, 12 kohm, ± 1%, 62.5 mW, 0402 [1005 Metric], Thick Film, General Purpose"
				(at 0 0 0)
				(effects
					(font
						(size 1.27 1.27)
					)
					(hide yes)
				)
			)
			(property "MPN" "CR0402-FX-1202GLF"
				(at 20.32 -20.32 0)
				(effects
					(font
						(size 1.27 1.27)
						(thickness 0.15)
					)
					(justify left bottom)
					(hide yes)
				)
			)
			(property "Manufacturer" "Bourns"
				(at 20.32 -22.86 0)
				(effects
					(font
						(size 1.27 1.27)
						(thickness 0.15)
					)
					(justify left bottom)
					(hide yes)
				)
			)
			(property "License" "Apache-2.0"
				(at 20.32 -25.4 0)
				(effects
					(font
						(size 1.27 1.27)
						(thickness 0.15)
					)
					(justify left bottom)
					(hide yes)
				)
			)
			(property "Author" "Antmicro"
				(at 20.32 -27.94 0)
				(effects
					(font
						(size 1.27 1.27)
						(thickness 0.15)
					)
					(justify left bottom)
					(hide yes)
				)
			)
			(property "Val" "12k"
				(at 20.32 -7.62 0)
				(effects
					(font
						(size 1.27 1.27)
						(thickness 0.15)
					)
					(justify left bottom)
				)
			)
			(property "Tolerance" "1%"
				(at 20.32 -10.16 0)
				(effects
					(font
						(size 1.27 1.27)
					)
					(justify left bottom)
					(hide yes)
				)
			)
			(property "ki_keywords" "0402, SMT, RESISTOR, PASSIVE"
				(at 0 0 0)
				(effects
					(font
						(size 1.27 1.27)
					)
					(hide yes)
				)
			)
			(symbol "R_12k_0402_0_1"
				(rectangle
					(start 0.635 0.889)
					(end 4.445 -0.889)
					(stroke
						(width 0.254)
						(type default)
					)
					(fill
						(type none)
					)
				)
			)
			(symbol "R_12k_0402_1_1"
				(pin passive line
					(at 0 0 0)
					(length 0.635)
					(name "~"
						(effects
							(font
								(size 1.27 1.27)
							)
						)
					)
					(number "1"
						(effects
							(font
								(size 1.27 1.27)
							)
						)
					)
				)
				(pin passive line
					(at 5.08 0 180)
					(length 0.635)
					(name "~"
						(effects
							(font
								(size 1.27 1.27)
							)
						)
					)
					(number "2"
						(effects
							(font
								(size 1.27 1.27)
							)
						)
					)
				)
			)
		)
	(symbol "antmicroResistors0402:R_15k_0402"
			(pin_numbers
				(hide yes)
			)
			(pin_names
				(hide yes)
			)
			(exclude_from_sim no)
			(in_bom yes)
			(on_board yes)
			(property "Reference" "R"
				(at 20.32 -5.08 0)
				(effects
					(font
						(size 1.27 1.27)
						(thickness 0.15)
					)
					(justify left bottom)
				)
			)
			(property "Value" "R_15k_0402"
				(at 20.32 -12.7 0)
				(effects
					(font
						(size 1.27 1.27)
						(thickness 0.15)
					)
					(justify left bottom)
					(hide yes)
				)
			)
			(property "Footprint" "antmicro-footprints:R_0402_1005Metric"
				(at 20.32 -15.24 0)
				(effects
					(font
						(size 1.27 1.27)
						(thickness 0.15)
					)
					(justify left bottom)
					(hide yes)
				)
			)
			(property "Datasheet" "https://www.bourns.com/docs/product-datasheets/cr.pdf"
				(at 20.32 -17.78 0)
				(effects
					(font
						(size 1.27 1.27)
						(thickness 0.15)
					)
					(justify left bottom)
					(hide yes)
				)
			)
			(property "Description" "SMD Chip Resistor, 15 kohm, ± 1%, 62.5 mW, 0402 [1005 Metric], Thick Film, General Purpose"
				(at 0 0 0)
				(effects
					(font
						(size 1.27 1.27)
					)
					(hide yes)
				)
			)
			(property "MPN" "CR0402-FX-1502GLF"
				(at 20.32 -20.32 0)
				(effects
					(font
						(size 1.27 1.27)
						(thickness 0.15)
					)
					(justify left bottom)
					(hide yes)
				)
			)
			(property "Manufacturer" "Bourns"
				(at 20.32 -22.86 0)
				(effects
					(font
						(size 1.27 1.27)
						(thickness 0.15)
					)
					(justify left bottom)
					(hide yes)
				)
			)
			(property "License" "Apache-2.0"
				(at 20.32 -25.4 0)
				(effects
					(font
						(size 1.27 1.27)
						(thickness 0.15)
					)
					(justify left bottom)
					(hide yes)
				)
			)
			(property "Author" "Antmicro"
				(at 20.32 -27.94 0)
				(effects
					(font
						(size 1.27 1.27)
						(thickness 0.15)
					)
					(justify left bottom)
					(hide yes)
				)
			)
			(property "Val" "15k"
				(at 20.32 -7.62 0)
				(effects
					(font
						(size 1.27 1.27)
						(thickness 0.15)
					)
					(justify left bottom)
				)
			)
			(property "Tolerance" "1%"
				(at 20.32 -10.16 0)
				(effects
					(font
						(size 1.27 1.27)
					)
					(justify left bottom)
					(hide yes)
				)
			)
			(property "ki_keywords" "0402, SMT, RESISTOR, PASSIVE"
				(at 0 0 0)
				(effects
					(font
						(size 1.27 1.27)
					)
					(hide yes)
				)
			)
			(symbol "R_15k_0402_0_1"
				(rectangle
					(start 0.635 0.889)
					(end 4.445 -0.889)
					(stroke
						(width 0.254)
						(type default)
					)
					(fill
						(type none)
					)
				)
			)
			(symbol "R_15k_0402_1_1"
				(pin passive line
					(at 0 0 0)
					(length 0.635)
					(name "~"
						(effects
							(font
								(size 1.27 1.27)
							)
						)
					)
					(number "1"
						(effects
							(font
								(size 1.27 1.27)
							)
						)
					)
				)
				(pin passive line
					(at 5.08 0 180)
					(length 0.635)
					(name "~"
						(effects
							(font
								(size 1.27 1.27)
							)
						)
					)
					(number "2"
						(effects
							(font
								(size 1.27 1.27)
							)
						)
					)
				)
			)
		)
	(symbol "antmicroResistors0402:R_1k2_0402"
			(pin_numbers
				(hide yes)
			)
			(pin_names
				(hide yes)
			)
			(exclude_from_sim no)
			(in_bom yes)
			(on_board yes)
			(property "Reference" "R"
				(at 20.32 -5.08 0)
				(effects
					(font
						(size 1.27 1.27)
						(thickness 0.15)
					)
					(justify left bottom)
				)
			)
			(property "Value" "R_1k2_0402"
				(at 20.32 -12.7 0)
				(effects
					(font
						(size 1.27 1.27)
						(thickness 0.15)
					)
					(justify left bottom)
					(hide yes)
				)
			)
			(property "Footprint" "antmicro-footprints:R_0402_1005Metric"
				(at 20.32 -15.24 0)
				(effects
					(font
						(size 1.27 1.27)
						(thickness 0.15)
					)
					(justify left bottom)
					(hide yes)
				)
			)
			(property "Datasheet" "https://www.bourns.com/docs/product-datasheets/cr.pdf"
				(at 20.32 -17.78 0)
				(effects
					(font
						(size 1.27 1.27)
						(thickness 0.15)
					)
					(justify left bottom)
					(hide yes)
				)
			)
			(property "Description" "SMD Chip Resistor, 1.2 kohm, ± 1%, 62.5 mW, 0402 [1005 Metric], Thick Film, General Purpose"
				(at 0 0 0)
				(effects
					(font
						(size 1.27 1.27)
					)
					(hide yes)
				)
			)
			(property "MPN" "CR0402-FX-1201GLF"
				(at 20.32 -20.32 0)
				(effects
					(font
						(size 1.27 1.27)
						(thickness 0.15)
					)
					(justify left bottom)
					(hide yes)
				)
			)
			(property "Manufacturer" "Bourns"
				(at 20.32 -22.86 0)
				(effects
					(font
						(size 1.27 1.27)
						(thickness 0.15)
					)
					(justify left bottom)
					(hide yes)
				)
			)
			(property "License" "Apache-2.0"
				(at 20.32 -25.4 0)
				(effects
					(font
						(size 1.27 1.27)
						(thickness 0.15)
					)
					(justify left bottom)
					(hide yes)
				)
			)
			(property "Author" "Antmicro"
				(at 20.32 -27.94 0)
				(effects
					(font
						(size 1.27 1.27)
						(thickness 0.15)
					)
					(justify left bottom)
					(hide yes)
				)
			)
			(property "Val" "1k2"
				(at 20.32 -7.62 0)
				(effects
					(font
						(size 1.27 1.27)
						(thickness 0.15)
					)
					(justify left bottom)
				)
			)
			(property "Tolerance" "1%"
				(at 20.32 -10.16 0)
				(effects
					(font
						(size 1.27 1.27)
					)
					(justify left bottom)
					(hide yes)
				)
			)
			(property "ki_keywords" "0402, SMT, RESISTOR, PASSIVE"
				(at 0 0 0)
				(effects
					(font
						(size 1.27 1.27)
					)
					(hide yes)
				)
			)
			(symbol "R_1k2_0402_0_1"
				(rectangle
					(start 0.635 0.889)
					(end 4.445 -0.889)
					(stroke
						(width 0.254)
						(type default)
					)
					(fill
						(type none)
					)
				)
			)
			(symbol "R_1k2_0402_1_1"
				(pin passive line
					(at 0 0 0)
					(length 0.635)
					(name "~"
						(effects
							(font
								(size 1.27 1.27)
							)
						)
					)
					(number "1"
						(effects
							(font
								(size 1.27 1.27)
							)
						)
					)
				)
				(pin passive line
					(at 5.08 0 180)
					(length 0.635)
					(name "~"
						(effects
							(font
								(size 1.27 1.27)
							)
						)
					)
					(number "2"
						(effects
							(font
								(size 1.27 1.27)
							)
						)
					)
				)
			)
		)
	(symbol "antmicroResistors0402:R_1k3_0402"
			(pin_numbers
				(hide yes)
			)
			(pin_names
				(hide yes)
			)
			(exclude_from_sim no)
			(in_bom yes)
			(on_board yes)
			(property "Reference" "R"
				(at 20.32 -5.08 0)
				(effects
					(font
						(size 1.27 1.27)
						(thickness 0.15)
					)
					(justify left bottom)
				)
			)
			(property "Value" "R_1k3_0402"
				(at 20.32 -12.7 0)
				(effects
					(font
						(size 1.27 1.27)
						(thickness 0.15)
					)
					(justify left bottom)
					(hide yes)
				)
			)
			(property "Footprint" "antmicro-footprints:R_0402_1005Metric"
				(at 20.32 -15.24 0)
				(effects
					(font
						(size 1.27 1.27)
						(thickness 0.15)
					)
					(justify left bottom)
					(hide yes)
				)
			)
			(property "Datasheet" "https://www.bourns.com/docs/product-datasheets/cr.pdf"
				(at 20.32 -17.78 0)
				(effects
					(font
						(size 1.27 1.27)
						(thickness 0.15)
					)
					(justify left bottom)
					(hide yes)
				)
			)
			(property "Description" "SMD Chip Resistor, 1.3 kohm, ± 1%, 62.5 mW, 0402 [1005 Metric], Thick Film, General Purpose"
				(at 0 0 0)
				(effects
					(font
						(size 1.27 1.27)
					)
					(hide yes)
				)
			)
			(property "MPN" "CR0402-FX-1301GLF"
				(at 20.32 -20.32 0)
				(effects
					(font
						(size 1.27 1.27)
						(thickness 0.15)
					)
					(justify left bottom)
					(hide yes)
				)
			)
			(property "Manufacturer" "Bourns"
				(at 20.32 -22.86 0)
				(effects
					(font
						(size 1.27 1.27)
						(thickness 0.15)
					)
					(justify left bottom)
					(hide yes)
				)
			)
			(property "License" "Apache-2.0"
				(at 20.32 -25.4 0)
				(effects
					(font
						(size 1.27 1.27)
						(thickness 0.15)
					)
					(justify left bottom)
					(hide yes)
				)
			)
			(property "Author" "Antmicro"
				(at 20.32 -27.94 0)
				(effects
					(font
						(size 1.27 1.27)
						(thickness 0.15)
					)
					(justify left bottom)
					(hide yes)
				)
			)
			(property "Val" "1k3"
				(at 20.32 -7.62 0)
				(effects
					(font
						(size 1.27 1.27)
						(thickness 0.15)
					)
					(justify left bottom)
				)
			)
			(property "Tolerance" "1%"
				(at 20.32 -10.16 0)
				(effects
					(font
						(size 1.27 1.27)
					)
					(justify left bottom)
					(hide yes)
				)
			)
			(property "ki_keywords" "0402, SMT, RESISTOR, PASSIVE"
				(at 0 0 0)
				(effects
					(font
						(size 1.27 1.27)
					)
					(hide yes)
				)
			)
			(symbol "R_1k3_0402_0_1"
				(rectangle
					(start 0.635 0.889)
					(end 4.445 -0.889)
					(stroke
						(width 0.254)
						(type default)
					)
					(fill
						(type none)
					)
				)
			)
			(symbol "R_1k3_0402_1_1"
				(pin passive line
					(at 0 0 0)
					(length 0.635)
					(name "~"
						(effects
							(font
								(size 1.27 1.27)
							)
						)
					)
					(number "1"
						(effects
							(font
								(size 1.27 1.27)
							)
						)
					)
				)
				(pin passive line
					(at 5.08 0 180)
					(length 0.635)
					(name "~"
						(effects
							(font
								(size 1.27 1.27)
							)
						)
					)
					(number "2"
						(effects
							(font
								(size 1.27 1.27)
							)
						)
					)
				)
			)
		)
	(symbol "antmicroResistors0402:R_1k_0402"
			(pin_numbers
				(hide yes)
			)
			(pin_names
				(hide yes)
			)
			(exclude_from_sim no)
			(in_bom yes)
			(on_board yes)
			(property "Reference" "R"
				(at 20.32 -5.08 0)
				(effects
					(font
						(size 1.27 1.27)
						(thickness 0.15)
					)
					(justify left bottom)
				)
			)
			(property "Value" "R_1k_0402"
				(at 20.32 -12.7 0)
				(effects
					(font
						(size 1.27 1.27)
						(thickness 0.15)
					)
					(justify left bottom)
					(hide yes)
				)
			)
			(property "Footprint" "antmicro-footprints:R_0402_1005Metric"
				(at 20.32 -15.24 0)
				(effects
					(font
						(size 1.27 1.27)
						(thickness 0.15)
					)
					(justify left bottom)
					(hide yes)
				)
			)
			(property "Datasheet" "https://www.bourns.com/docs/product-datasheets/cr.pdf"
				(at 20.32 -17.78 0)
				(effects
					(font
						(size 1.27 1.27)
						(thickness 0.15)
					)
					(justify left bottom)
					(hide yes)
				)
			)
			(property "Description" "SMD Chip Resistor, 1 kohm, ± 1%, 63 mW, 0402 [1005 Metric], Thick Film, General Purpose"
				(at 0 0 0)
				(effects
					(font
						(size 1.27 1.27)
					)
					(hide yes)
				)
			)
			(property "MPN" "CR0402-FX-1001GLF"
				(at 20.32 -20.32 0)
				(effects
					(font
						(size 1.27 1.27)
						(thickness 0.15)
					)
					(justify left bottom)
					(hide yes)
				)
			)
			(property "Manufacturer" "Bourns"
				(at 20.32 -22.86 0)
				(effects
					(font
						(size 1.27 1.27)
						(thickness 0.15)
					)
					(justify left bottom)
					(hide yes)
				)
			)
			(property "License" "Apache-2.0"
				(at 20.32 -25.4 0)
				(effects
					(font
						(size 1.27 1.27)
						(thickness 0.15)
					)
					(justify left bottom)
					(hide yes)
				)
			)
			(property "Author" "Antmicro"
				(at 20.32 -27.94 0)
				(effects
					(font
						(size 1.27 1.27)
						(thickness 0.15)
					)
					(justify left bottom)
					(hide yes)
				)
			)
			(property "Val" "1k"
				(at 20.32 -7.62 0)
				(effects
					(font
						(size 1.27 1.27)
						(thickness 0.15)
					)
					(justify left bottom)
				)
			)
			(property "Tolerance" "1%"
				(at 20.32 -10.16 0)
				(effects
					(font
						(size 1.27 1.27)
					)
					(justify left bottom)
					(hide yes)
				)
			)
			(property "ki_keywords" "0402, SMT, RESISTOR, PASSIVE"
				(at 0 0 0)
				(effects
					(font
						(size 1.27 1.27)
					)
					(hide yes)
				)
			)
			(symbol "R_1k_0402_0_1"
				(rectangle
					(start 0.635 0.889)
					(end 4.445 -0.889)
					(stroke
						(width 0.254)
						(type default)
					)
					(fill
						(type none)
					)
				)
			)
			(symbol "R_1k_0402_1_1"
				(pin passive line
					(at 0 0 0)
					(length 0.635)
					(name "~"
						(effects
							(font
								(size 1.27 1.27)
							)
						)
					)
					(number "1"
						(effects
							(font
								(size 1.27 1.27)
							)
						)
					)
				)
				(pin passive line
					(at 5.08 0 180)
					(length 0.635)
					(name "~"
						(effects
							(font
								(size 1.27 1.27)
							)
						)
					)
					(number "2"
						(effects
							(font
								(size 1.27 1.27)
							)
						)
					)
				)
			)
		)
	(symbol "antmicroResistors0402:R_200R_0402"
			(pin_numbers
				(hide yes)
			)
			(pin_names
				(hide yes)
			)
			(exclude_from_sim no)
			(in_bom yes)
			(on_board yes)
			(property "Reference" "R"
				(at 20.32 -5.08 0)
				(effects
					(font
						(size 1.27 1.27)
						(thickness 0.15)
					)
					(justify left bottom)
				)
			)
			(property "Value" "R_200R_0402"
				(at 20.32 -12.7 0)
				(effects
					(font
						(size 1.27 1.27)
						(thickness 0.15)
					)
					(justify left bottom)
					(hide yes)
				)
			)
			(property "Footprint" "antmicro-footprints:R_0402_1005Metric"
				(at 20.32 -15.24 0)
				(effects
					(font
						(size 1.27 1.27)
						(thickness 0.15)
					)
					(justify left bottom)
					(hide yes)
				)
			)
			(property "Datasheet" "https://www.bourns.com/docs/product-datasheets/cr.pdf"
				(at 20.32 -17.78 0)
				(effects
					(font
						(size 1.27 1.27)
						(thickness 0.15)
					)
					(justify left bottom)
					(hide yes)
				)
			)
			(property "Description" "SMD Chip Resistor, 200 ohm, ± 1%, 62.5 mW, 0402 [1005 Metric], Thick Film, General Purpose"
				(at 0 0 0)
				(effects
					(font
						(size 1.27 1.27)
					)
					(hide yes)
				)
			)
			(property "MPN" "CR0402-FX-2000GLF"
				(at 20.32 -20.32 0)
				(effects
					(font
						(size 1.27 1.27)
						(thickness 0.15)
					)
					(justify left bottom)
					(hide yes)
				)
			)
			(property "Manufacturer" "Bourns"
				(at 20.32 -22.86 0)
				(effects
					(font
						(size 1.27 1.27)
						(thickness 0.15)
					)
					(justify left bottom)
					(hide yes)
				)
			)
			(property "License" "Apache-2.0"
				(at 20.32 -25.4 0)
				(effects
					(font
						(size 1.27 1.27)
						(thickness 0.15)
					)
					(justify left bottom)
					(hide yes)
				)
			)
			(property "Author" "Antmicro"
				(at 20.32 -27.94 0)
				(effects
					(font
						(size 1.27 1.27)
						(thickness 0.15)
					)
					(justify left bottom)
					(hide yes)
				)
			)
			(property "Val" "200R"
				(at 20.32 -7.62 0)
				(effects
					(font
						(size 1.27 1.27)
						(thickness 0.15)
					)
					(justify left bottom)
				)
			)
			(property "Tolerance" "1%"
				(at 20.32 -10.16 0)
				(effects
					(font
						(size 1.27 1.27)
					)
					(justify left bottom)
					(hide yes)
				)
			)
			(property "ki_keywords" "0402, SMT, RESISTOR, PASSIVE"
				(at 0 0 0)
				(effects
					(font
						(size 1.27 1.27)
					)
					(hide yes)
				)
			)
			(symbol "R_200R_0402_0_1"
				(rectangle
					(start 0.635 0.889)
					(end 4.445 -0.889)
					(stroke
						(width 0.254)
						(type default)
					)
					(fill
						(type none)
					)
				)
			)
			(symbol "R_200R_0402_1_1"
				(pin passive line
					(at 0 0 0)
					(length 0.635)
					(name "~"
						(effects
							(font
								(size 1.27 1.27)
							)
						)
					)
					(number "1"
						(effects
							(font
								(size 1.27 1.27)
							)
						)
					)
				)
				(pin passive line
					(at 5.08 0 180)
					(length 0.635)
					(name "~"
						(effects
							(font
								(size 1.27 1.27)
							)
						)
					)
					(number "2"
						(effects
							(font
								(size 1.27 1.27)
							)
						)
					)
				)
			)
		)
	(symbol "antmicroResistors0402:R_24k9_0402"
			(pin_numbers
				(hide yes)
			)
			(pin_names
				(hide yes)
			)
			(exclude_from_sim no)
			(in_bom yes)
			(on_board yes)
			(property "Reference" "R"
				(at 20.32 -5.08 0)
				(effects
					(font
						(size 1.27 1.27)
						(thickness 0.15)
					)
					(justify left bottom)
				)
			)
			(property "Value" "R_24k9_0402"
				(at 20.32 -12.7 0)
				(effects
					(font
						(size 1.27 1.27)
						(thickness 0.15)
					)
					(justify left bottom)
					(hide yes)
				)
			)
			(property "Footprint" "antmicro-footprints:R_0402_1005Metric"
				(at 20.32 -15.24 0)
				(effects
					(font
						(size 1.27 1.27)
						(thickness 0.15)
					)
					(justify left bottom)
					(hide yes)
				)
			)
			(property "Datasheet" "https://www.bourns.com/docs/product-datasheets/cr.pdf"
				(at 20.32 -17.78 0)
				(effects
					(font
						(size 1.27 1.27)
						(thickness 0.15)
					)
					(justify left bottom)
					(hide yes)
				)
			)
			(property "Description" "SMD Chip Resistor, 24.9 kohm, ± 1%, 63 mW, 0402 [1005 Metric], Thick Film, General Purpose"
				(at 0 0 0)
				(effects
					(font
						(size 1.27 1.27)
					)
					(hide yes)
				)
			)
			(property "MPN" "CR0402-FX-2492GLF"
				(at 20.32 -20.32 0)
				(effects
					(font
						(size 1.27 1.27)
						(thickness 0.15)
					)
					(justify left bottom)
					(hide yes)
				)
			)
			(property "Manufacturer" "Bourns"
				(at 20.32 -22.86 0)
				(effects
					(font
						(size 1.27 1.27)
						(thickness 0.15)
					)
					(justify left bottom)
					(hide yes)
				)
			)
			(property "License" "Apache-2.0"
				(at 20.32 -25.4 0)
				(effects
					(font
						(size 1.27 1.27)
						(thickness 0.15)
					)
					(justify left bottom)
					(hide yes)
				)
			)
			(property "Author" "Antmicro"
				(at 20.32 -27.94 0)
				(effects
					(font
						(size 1.27 1.27)
						(thickness 0.15)
					)
					(justify left bottom)
					(hide yes)
				)
			)
			(property "Val" "24k9"
				(at 20.32 -7.62 0)
				(effects
					(font
						(size 1.27 1.27)
						(thickness 0.15)
					)
					(justify left bottom)
				)
			)
			(property "Tolerance" "1%"
				(at 20.32 -10.16 0)
				(effects
					(font
						(size 1.27 1.27)
					)
					(justify left bottom)
					(hide yes)
				)
			)
			(property "ki_keywords" "0402, SMT, RESISTOR, PASSIVE"
				(at 0 0 0)
				(effects
					(font
						(size 1.27 1.27)
					)
					(hide yes)
				)
			)
			(symbol "R_24k9_0402_0_1"
				(rectangle
					(start 0.635 0.889)
					(end 4.445 -0.889)
					(stroke
						(width 0.254)
						(type default)
					)
					(fill
						(type none)
					)
				)
			)
			(symbol "R_24k9_0402_1_1"
				(pin passive line
					(at 0 0 0)
					(length 0.635)
					(name "~"
						(effects
							(font
								(size 1.27 1.27)
							)
						)
					)
					(number "1"
						(effects
							(font
								(size 1.27 1.27)
							)
						)
					)
				)
				(pin passive line
					(at 5.08 0 180)
					(length 0.635)
					(name "~"
						(effects
							(font
								(size 1.27 1.27)
							)
						)
					)
					(number "2"
						(effects
							(font
								(size 1.27 1.27)
							)
						)
					)
				)
			)
		)
	(symbol "antmicroResistors0402:R_2k2_0402"
			(pin_numbers
				(hide yes)
			)
			(pin_names
				(hide yes)
			)
			(exclude_from_sim no)
			(in_bom yes)
			(on_board yes)
			(property "Reference" "R"
				(at 20.32 -5.08 0)
				(effects
					(font
						(size 1.27 1.27)
						(thickness 0.15)
					)
					(justify left bottom)
				)
			)
			(property "Value" "R_2k2_0402"
				(at 20.32 -12.7 0)
				(effects
					(font
						(size 1.27 1.27)
						(thickness 0.15)
					)
					(justify left bottom)
					(hide yes)
				)
			)
			(property "Footprint" "antmicro-footprints:R_0402_1005Metric"
				(at 20.32 -15.24 0)
				(effects
					(font
						(size 1.27 1.27)
						(thickness 0.15)
					)
					(justify left bottom)
					(hide yes)
				)
			)
			(property "Datasheet" "https://www.bourns.com/docs/product-datasheets/cr.pdf"
				(at 20.32 -17.78 0)
				(effects
					(font
						(size 1.27 1.27)
						(thickness 0.15)
					)
					(justify left bottom)
					(hide yes)
				)
			)
			(property "Description" "SMD Chip Resistor, 2.2 kohm, ± 1%, 62.5 mW, 0402 [1005 Metric], Thick Film, General Purpose"
				(at 0 0 0)
				(effects
					(font
						(size 1.27 1.27)
					)
					(hide yes)
				)
			)
			(property "MPN" "CR0402-FX-2201GLF"
				(at 20.32 -20.32 0)
				(effects
					(font
						(size 1.27 1.27)
						(thickness 0.15)
					)
					(justify left bottom)
					(hide yes)
				)
			)
			(property "Manufacturer" "Bourns"
				(at 20.32 -22.86 0)
				(effects
					(font
						(size 1.27 1.27)
						(thickness 0.15)
					)
					(justify left bottom)
					(hide yes)
				)
			)
			(property "License" "Apache-2.0"
				(at 20.32 -25.4 0)
				(effects
					(font
						(size 1.27 1.27)
						(thickness 0.15)
					)
					(justify left bottom)
					(hide yes)
				)
			)
			(property "Author" "Antmicro"
				(at 20.32 -27.94 0)
				(effects
					(font
						(size 1.27 1.27)
						(thickness 0.15)
					)
					(justify left bottom)
					(hide yes)
				)
			)
			(property "Val" "2k2"
				(at 20.32 -7.62 0)
				(effects
					(font
						(size 1.27 1.27)
						(thickness 0.15)
					)
					(justify left bottom)
				)
			)
			(property "Tolerance" "1%"
				(at 20.32 -10.16 0)
				(effects
					(font
						(size 1.27 1.27)
					)
					(justify left bottom)
					(hide yes)
				)
			)
			(property "ki_keywords" "0402, SMT, RESISTOR, PASSIVE"
				(at 0 0 0)
				(effects
					(font
						(size 1.27 1.27)
					)
					(hide yes)
				)
			)
			(symbol "R_2k2_0402_0_1"
				(rectangle
					(start 0.635 0.889)
					(end 4.445 -0.889)
					(stroke
						(width 0.254)
						(type default)
					)
					(fill
						(type none)
					)
				)
			)
			(symbol "R_2k2_0402_1_1"
				(pin passive line
					(at 0 0 0)
					(length 0.635)
					(name "~"
						(effects
							(font
								(size 1.27 1.27)
							)
						)
					)
					(number "1"
						(effects
							(font
								(size 1.27 1.27)
							)
						)
					)
				)
				(pin passive line
					(at 5.08 0 180)
					(length 0.635)
					(name "~"
						(effects
							(font
								(size 1.27 1.27)
							)
						)
					)
					(number "2"
						(effects
							(font
								(size 1.27 1.27)
							)
						)
					)
				)
			)
		)
	(symbol "antmicroResistors0402:R_2k_0402"
			(pin_numbers
				(hide yes)
			)
			(pin_names
				(hide yes)
			)
			(exclude_from_sim no)
			(in_bom yes)
			(on_board yes)
			(property "Reference" "R"
				(at 20.32 -5.08 0)
				(effects
					(font
						(size 1.27 1.27)
						(thickness 0.15)
					)
					(justify left bottom)
				)
			)
			(property "Value" "R_2k_0402"
				(at 20.32 -12.7 0)
				(effects
					(font
						(size 1.27 1.27)
						(thickness 0.15)
					)
					(justify left bottom)
					(hide yes)
				)
			)
			(property "Footprint" "antmicro-footprints:R_0402_1005Metric"
				(at 20.32 -15.24 0)
				(effects
					(font
						(size 1.27 1.27)
						(thickness 0.15)
					)
					(justify left bottom)
					(hide yes)
				)
			)
			(property "Datasheet" "https://www.bourns.com/docs/product-datasheets/cr.pdf"
				(at 20.32 -17.78 0)
				(effects
					(font
						(size 1.27 1.27)
						(thickness 0.15)
					)
					(justify left bottom)
					(hide yes)
				)
			)
			(property "Description" "SMD Chip Resistor, 2 kohm, ± 1%, 62.5 mW, 0402 [1005 Metric], Thick Film, General Purpose"
				(at 0 0 0)
				(effects
					(font
						(size 1.27 1.27)
					)
					(hide yes)
				)
			)
			(property "MPN" "CR0402-FX-2001GLF"
				(at 20.32 -20.32 0)
				(effects
					(font
						(size 1.27 1.27)
						(thickness 0.15)
					)
					(justify left bottom)
					(hide yes)
				)
			)
			(property "Manufacturer" "Bourns"
				(at 20.32 -22.86 0)
				(effects
					(font
						(size 1.27 1.27)
						(thickness 0.15)
					)
					(justify left bottom)
					(hide yes)
				)
			)
			(property "License" "Apache-2.0"
				(at 20.32 -25.4 0)
				(effects
					(font
						(size 1.27 1.27)
						(thickness 0.15)
					)
					(justify left bottom)
					(hide yes)
				)
			)
			(property "Author" "Antmicro"
				(at 20.32 -27.94 0)
				(effects
					(font
						(size 1.27 1.27)
						(thickness 0.15)
					)
					(justify left bottom)
					(hide yes)
				)
			)
			(property "Val" "2k"
				(at 20.32 -7.62 0)
				(effects
					(font
						(size 1.27 1.27)
						(thickness 0.15)
					)
					(justify left bottom)
				)
			)
			(property "Tolerance" "1%"
				(at 20.32 -10.16 0)
				(effects
					(font
						(size 1.27 1.27)
					)
					(justify left bottom)
					(hide yes)
				)
			)
			(property "ki_keywords" "0402, SMT, RESISTOR, PASSIVE"
				(at 0 0 0)
				(effects
					(font
						(size 1.27 1.27)
					)
					(hide yes)
				)
			)
			(symbol "R_2k_0402_0_1"
				(rectangle
					(start 0.635 0.889)
					(end 4.445 -0.889)
					(stroke
						(width 0.254)
						(type default)
					)
					(fill
						(type none)
					)
				)
			)
			(symbol "R_2k_0402_1_1"
				(pin passive line
					(at 0 0 0)
					(length 0.635)
					(name "~"
						(effects
							(font
								(size 1.27 1.27)
							)
						)
					)
					(number "1"
						(effects
							(font
								(size 1.27 1.27)
							)
						)
					)
				)
				(pin passive line
					(at 5.08 0 180)
					(length 0.635)
					(name "~"
						(effects
							(font
								(size 1.27 1.27)
							)
						)
					)
					(number "2"
						(effects
							(font
								(size 1.27 1.27)
							)
						)
					)
				)
			)
		)
	(symbol "antmicroResistors0402:R_33k_0402"
			(pin_numbers
				(hide yes)
			)
			(pin_names
				(hide yes)
			)
			(exclude_from_sim no)
			(in_bom yes)
			(on_board yes)
			(property "Reference" "R"
				(at 20.32 -5.08 0)
				(effects
					(font
						(size 1.27 1.27)
						(thickness 0.15)
					)
					(justify left bottom)
				)
			)
			(property "Value" "R_33k_0402"
				(at 20.32 -12.7 0)
				(effects
					(font
						(size 1.27 1.27)
						(thickness 0.15)
					)
					(justify left bottom)
					(hide yes)
				)
			)
			(property "Footprint" "antmicro-footprints:R_0402_1005Metric"
				(at 20.32 -15.24 0)
				(effects
					(font
						(size 1.27 1.27)
						(thickness 0.15)
					)
					(justify left bottom)
					(hide yes)
				)
			)
			(property "Datasheet" "https://www.bourns.com/docs/product-datasheets/cr.pdf"
				(at 20.32 -17.78 0)
				(effects
					(font
						(size 1.27 1.27)
						(thickness 0.15)
					)
					(justify left bottom)
					(hide yes)
				)
			)
			(property "Description" "SMD Chip Resistor, 33 kohm, ± 1%, 62.5 mW, 0402 [1005 Metric], Thick Film, General Purpose"
				(at 0 0 0)
				(effects
					(font
						(size 1.27 1.27)
					)
					(hide yes)
				)
			)
			(property "MPN" "CR0402-FX-3302GLF"
				(at 20.32 -20.32 0)
				(effects
					(font
						(size 1.27 1.27)
						(thickness 0.15)
					)
					(justify left bottom)
					(hide yes)
				)
			)
			(property "Manufacturer" "Bourns"
				(at 20.32 -22.86 0)
				(effects
					(font
						(size 1.27 1.27)
						(thickness 0.15)
					)
					(justify left bottom)
					(hide yes)
				)
			)
			(property "License" "Apache-2.0"
				(at 20.32 -25.4 0)
				(effects
					(font
						(size 1.27 1.27)
						(thickness 0.15)
					)
					(justify left bottom)
					(hide yes)
				)
			)
			(property "Author" "Antmicro"
				(at 20.32 -27.94 0)
				(effects
					(font
						(size 1.27 1.27)
						(thickness 0.15)
					)
					(justify left bottom)
					(hide yes)
				)
			)
			(property "Val" "33k"
				(at 20.32 -7.62 0)
				(effects
					(font
						(size 1.27 1.27)
						(thickness 0.15)
					)
					(justify left bottom)
				)
			)
			(property "Tolerance" "1%"
				(at 20.32 -10.16 0)
				(effects
					(font
						(size 1.27 1.27)
					)
					(justify left bottom)
					(hide yes)
				)
			)
			(property "ki_keywords" "0402, SMT, RESISTOR, PASSIVE"
				(at 0 0 0)
				(effects
					(font
						(size 1.27 1.27)
					)
					(hide yes)
				)
			)
			(symbol "R_33k_0402_0_1"
				(rectangle
					(start 0.635 0.889)
					(end 4.445 -0.889)
					(stroke
						(width 0.254)
						(type default)
					)
					(fill
						(type none)
					)
				)
			)
			(symbol "R_33k_0402_1_1"
				(pin passive line
					(at 0 0 0)
					(length 0.635)
					(name "~"
						(effects
							(font
								(size 1.27 1.27)
							)
						)
					)
					(number "1"
						(effects
							(font
								(size 1.27 1.27)
							)
						)
					)
				)
				(pin passive line
					(at 5.08 0 180)
					(length 0.635)
					(name "~"
						(effects
							(font
								(size 1.27 1.27)
							)
						)
					)
					(number "2"
						(effects
							(font
								(size 1.27 1.27)
							)
						)
					)
				)
			)
		)
	(symbol "antmicroResistors0402:R_470R_0402"
			(pin_numbers
				(hide yes)
			)
			(pin_names
				(hide yes)
			)
			(exclude_from_sim no)
			(in_bom yes)
			(on_board yes)
			(property "Reference" "R"
				(at 20.32 -5.08 0)
				(effects
					(font
						(size 1.27 1.27)
						(thickness 0.15)
					)
					(justify left bottom)
				)
			)
			(property "Value" "R_470R_0402"
				(at 20.32 -12.7 0)
				(effects
					(font
						(size 1.27 1.27)
						(thickness 0.15)
					)
					(justify left bottom)
					(hide yes)
				)
			)
			(property "Footprint" "antmicro-footprints:R_0402_1005Metric"
				(at 20.32 -15.24 0)
				(effects
					(font
						(size 1.27 1.27)
						(thickness 0.15)
					)
					(justify left bottom)
					(hide yes)
				)
			)
			(property "Datasheet" "https://www.bourns.com/docs/product-datasheets/cr.pdf"
				(at 20.32 -17.78 0)
				(effects
					(font
						(size 1.27 1.27)
						(thickness 0.15)
					)
					(justify left bottom)
					(hide yes)
				)
			)
			(property "Description" "SMD Chip Resistor, 470 ohm, ± 1%, 62.5 mW, 0402 [1005 Metric], Thick Film, General Purpose"
				(at 0 0 0)
				(effects
					(font
						(size 1.27 1.27)
					)
					(hide yes)
				)
			)
			(property "MPN" "CR0402-FX-4700GLF"
				(at 20.32 -20.32 0)
				(effects
					(font
						(size 1.27 1.27)
						(thickness 0.15)
					)
					(justify left bottom)
					(hide yes)
				)
			)
			(property "Manufacturer" "Bourns"
				(at 20.32 -22.86 0)
				(effects
					(font
						(size 1.27 1.27)
						(thickness 0.15)
					)
					(justify left bottom)
					(hide yes)
				)
			)
			(property "License" "Apache-2.0"
				(at 20.32 -25.4 0)
				(effects
					(font
						(size 1.27 1.27)
						(thickness 0.15)
					)
					(justify left bottom)
					(hide yes)
				)
			)
			(property "Author" "Antmicro"
				(at 20.32 -27.94 0)
				(effects
					(font
						(size 1.27 1.27)
						(thickness 0.15)
					)
					(justify left bottom)
					(hide yes)
				)
			)
			(property "Val" "470R"
				(at 20.32 -7.62 0)
				(effects
					(font
						(size 1.27 1.27)
						(thickness 0.15)
					)
					(justify left bottom)
				)
			)
			(property "Tolerance" "1%"
				(at 20.32 -10.16 0)
				(effects
					(font
						(size 1.27 1.27)
					)
					(justify left bottom)
					(hide yes)
				)
			)
			(property "ki_keywords" "0402, SMT, RESISTOR, PASSIVE"
				(at 0 0 0)
				(effects
					(font
						(size 1.27 1.27)
					)
					(hide yes)
				)
			)
			(symbol "R_470R_0402_0_1"
				(rectangle
					(start 0.635 0.889)
					(end 4.445 -0.889)
					(stroke
						(width 0.254)
						(type default)
					)
					(fill
						(type none)
					)
				)
			)
			(symbol "R_470R_0402_1_1"
				(pin passive line
					(at 0 0 0)
					(length 0.635)
					(name "~"
						(effects
							(font
								(size 1.27 1.27)
							)
						)
					)
					(number "1"
						(effects
							(font
								(size 1.27 1.27)
							)
						)
					)
				)
				(pin passive line
					(at 5.08 0 180)
					(length 0.635)
					(name "~"
						(effects
							(font
								(size 1.27 1.27)
							)
						)
					)
					(number "2"
						(effects
							(font
								(size 1.27 1.27)
							)
						)
					)
				)
			)
		)
	(symbol "antmicroResistors0402:R_470k_0402"
			(pin_numbers
				(hide yes)
			)
			(pin_names
				(hide yes)
			)
			(exclude_from_sim no)
			(in_bom yes)
			(on_board yes)
			(property "Reference" "R"
				(at 20.32 -5.08 0)
				(effects
					(font
						(size 1.27 1.27)
						(thickness 0.15)
					)
					(justify left bottom)
				)
			)
			(property "Value" "R_470k_0402"
				(at 20.32 -12.7 0)
				(effects
					(font
						(size 1.27 1.27)
						(thickness 0.15)
					)
					(justify left bottom)
					(hide yes)
				)
			)
			(property "Footprint" "antmicro-footprints:R_0402_1005Metric"
				(at 20.32 -15.24 0)
				(effects
					(font
						(size 1.27 1.27)
						(thickness 0.15)
					)
					(justify left bottom)
					(hide yes)
				)
			)
			(property "Datasheet" "https://www.bourns.com/docs/product-datasheets/cr.pdf"
				(at 20.32 -17.78 0)
				(effects
					(font
						(size 1.27 1.27)
						(thickness 0.15)
					)
					(justify left bottom)
					(hide yes)
				)
			)
			(property "Description" "SMD Chip Resistor, 470 kohm, ± 1%, 62.5 mW, 0402 [1005 Metric], Thick Film, Sulfur Resistant"
				(at 0 0 0)
				(effects
					(font
						(size 1.27 1.27)
					)
					(hide yes)
				)
			)
			(property "MPN" "CR0402-FX-4703GLF"
				(at 20.32 -20.32 0)
				(effects
					(font
						(size 1.27 1.27)
						(thickness 0.15)
					)
					(justify left bottom)
					(hide yes)
				)
			)
			(property "Manufacturer" "Bourns"
				(at 20.32 -22.86 0)
				(effects
					(font
						(size 1.27 1.27)
						(thickness 0.15)
					)
					(justify left bottom)
					(hide yes)
				)
			)
			(property "License" "Apache-2.0"
				(at 20.32 -25.4 0)
				(effects
					(font
						(size 1.27 1.27)
						(thickness 0.15)
					)
					(justify left bottom)
					(hide yes)
				)
			)
			(property "Author" "Antmicro"
				(at 20.32 -27.94 0)
				(effects
					(font
						(size 1.27 1.27)
						(thickness 0.15)
					)
					(justify left bottom)
					(hide yes)
				)
			)
			(property "Val" "470k"
				(at 20.32 -7.62 0)
				(effects
					(font
						(size 1.27 1.27)
						(thickness 0.15)
					)
					(justify left bottom)
				)
			)
			(property "Tolerance" "1%"
				(at 20.32 -10.16 0)
				(effects
					(font
						(size 1.27 1.27)
					)
					(justify left bottom)
					(hide yes)
				)
			)
			(property "ki_keywords" "0402, SMT, RESISTOR, PASSIVE"
				(at 0 0 0)
				(effects
					(font
						(size 1.27 1.27)
					)
					(hide yes)
				)
			)
			(symbol "R_470k_0402_0_1"
				(rectangle
					(start 0.635 0.889)
					(end 4.445 -0.889)
					(stroke
						(width 0.254)
						(type default)
					)
					(fill
						(type none)
					)
				)
			)
			(symbol "R_470k_0402_1_1"
				(pin passive line
					(at 0 0 0)
					(length 0.635)
					(name "~"
						(effects
							(font
								(size 1.27 1.27)
							)
						)
					)
					(number "1"
						(effects
							(font
								(size 1.27 1.27)
							)
						)
					)
				)
				(pin passive line
					(at 5.08 0 180)
					(length 0.635)
					(name "~"
						(effects
							(font
								(size 1.27 1.27)
							)
						)
					)
					(number "2"
						(effects
							(font
								(size 1.27 1.27)
							)
						)
					)
				)
			)
		)
	(symbol "antmicroResistors0402:R_49k9_0402"
			(pin_numbers
				(hide yes)
			)
			(pin_names
				(hide yes)
			)
			(exclude_from_sim no)
			(in_bom yes)
			(on_board yes)
			(property "Reference" "R"
				(at 20.32 -5.08 0)
				(effects
					(font
						(size 1.27 1.27)
						(thickness 0.15)
					)
					(justify left bottom)
				)
			)
			(property "Value" "R_49k9_0402"
				(at 20.32 -12.7 0)
				(effects
					(font
						(size 1.27 1.27)
						(thickness 0.15)
					)
					(justify left bottom)
					(hide yes)
				)
			)
			(property "Footprint" "antmicro-footprints:R_0402_1005Metric"
				(at 20.32 -15.24 0)
				(effects
					(font
						(size 1.27 1.27)
						(thickness 0.15)
					)
					(justify left bottom)
					(hide yes)
				)
			)
			(property "Datasheet" "https://www.bourns.com/docs/product-datasheets/cr.pdf"
				(at 20.32 -17.78 0)
				(effects
					(font
						(size 1.27 1.27)
						(thickness 0.15)
					)
					(justify left bottom)
					(hide yes)
				)
			)
			(property "Description" "SMD Chip Resistor, 49.9 kohm, ± 1%, 63 mW, 0402 [1005 Metric], Thick Film, General Purpose"
				(at 0 0 0)
				(effects
					(font
						(size 1.27 1.27)
					)
					(hide yes)
				)
			)
			(property "MPN" "CR0402-FX-4992GLF"
				(at 20.32 -20.32 0)
				(effects
					(font
						(size 1.27 1.27)
						(thickness 0.15)
					)
					(justify left bottom)
					(hide yes)
				)
			)
			(property "Manufacturer" "Bourns"
				(at 20.32 -22.86 0)
				(effects
					(font
						(size 1.27 1.27)
						(thickness 0.15)
					)
					(justify left bottom)
					(hide yes)
				)
			)
			(property "License" "Apache-2.0"
				(at 20.32 -25.4 0)
				(effects
					(font
						(size 1.27 1.27)
						(thickness 0.15)
					)
					(justify left bottom)
					(hide yes)
				)
			)
			(property "Author" "Antmicro"
				(at 20.32 -27.94 0)
				(effects
					(font
						(size 1.27 1.27)
						(thickness 0.15)
					)
					(justify left bottom)
					(hide yes)
				)
			)
			(property "Val" "49k9"
				(at 20.32 -7.62 0)
				(effects
					(font
						(size 1.27 1.27)
						(thickness 0.15)
					)
					(justify left bottom)
				)
			)
			(property "Tolerance" "1%"
				(at 20.32 -10.16 0)
				(effects
					(font
						(size 1.27 1.27)
					)
					(justify left bottom)
					(hide yes)
				)
			)
			(property "ki_keywords" "0402, SMT, RESISTOR, PASSIVE"
				(at 0 0 0)
				(effects
					(font
						(size 1.27 1.27)
					)
					(hide yes)
				)
			)
			(symbol "R_49k9_0402_0_1"
				(rectangle
					(start 0.635 0.889)
					(end 4.445 -0.889)
					(stroke
						(width 0.254)
						(type default)
					)
					(fill
						(type none)
					)
				)
			)
			(symbol "R_49k9_0402_1_1"
				(pin passive line
					(at 0 0 0)
					(length 0.635)
					(name "~"
						(effects
							(font
								(size 1.27 1.27)
							)
						)
					)
					(number "1"
						(effects
							(font
								(size 1.27 1.27)
							)
						)
					)
				)
				(pin passive line
					(at 5.08 0 180)
					(length 0.635)
					(name "~"
						(effects
							(font
								(size 1.27 1.27)
							)
						)
					)
					(number "2"
						(effects
							(font
								(size 1.27 1.27)
							)
						)
					)
				)
			)
		)
	(symbol "antmicroResistors0402:R_4k7_0402"
			(pin_numbers
				(hide yes)
			)
			(pin_names
				(hide yes)
			)
			(exclude_from_sim no)
			(in_bom yes)
			(on_board yes)
			(property "Reference" "R"
				(at 20.32 -5.08 0)
				(effects
					(font
						(size 1.27 1.27)
						(thickness 0.15)
					)
					(justify left bottom)
				)
			)
			(property "Value" "R_4k7_0402"
				(at 20.32 -12.7 0)
				(effects
					(font
						(size 1.27 1.27)
						(thickness 0.15)
					)
					(justify left bottom)
					(hide yes)
				)
			)
			(property "Footprint" "antmicro-footprints:R_0402_1005Metric"
				(at 20.32 -15.24 0)
				(effects
					(font
						(size 1.27 1.27)
						(thickness 0.15)
					)
					(justify left bottom)
					(hide yes)
				)
			)
			(property "Datasheet" "https://www.bourns.com/docs/product-datasheets/cr.pdf"
				(at 20.32 -17.78 0)
				(effects
					(font
						(size 1.27 1.27)
						(thickness 0.15)
					)
					(justify left bottom)
					(hide yes)
				)
			)
			(property "Description" "SMD Chip Resistor, 4.7 kohm, ± 1%, 62.5 mW, 0402 [1005 Metric], Thick Film, General Purpose"
				(at 0 0 0)
				(effects
					(font
						(size 1.27 1.27)
					)
					(hide yes)
				)
			)
			(property "MPN" "CR0402-FX-4701GLF"
				(at 20.32 -20.32 0)
				(effects
					(font
						(size 1.27 1.27)
						(thickness 0.15)
					)
					(justify left bottom)
					(hide yes)
				)
			)
			(property "Manufacturer" "Bourns"
				(at 20.32 -22.86 0)
				(effects
					(font
						(size 1.27 1.27)
						(thickness 0.15)
					)
					(justify left bottom)
					(hide yes)
				)
			)
			(property "License" "Apache-2.0"
				(at 20.32 -25.4 0)
				(effects
					(font
						(size 1.27 1.27)
						(thickness 0.15)
					)
					(justify left bottom)
					(hide yes)
				)
			)
			(property "Author" "Antmicro"
				(at 20.32 -27.94 0)
				(effects
					(font
						(size 1.27 1.27)
						(thickness 0.15)
					)
					(justify left bottom)
					(hide yes)
				)
			)
			(property "Val" "4k7"
				(at 20.32 -7.62 0)
				(effects
					(font
						(size 1.27 1.27)
						(thickness 0.15)
					)
					(justify left bottom)
				)
			)
			(property "Tolerance" "1%"
				(at 20.32 -10.16 0)
				(effects
					(font
						(size 1.27 1.27)
					)
					(justify left bottom)
					(hide yes)
				)
			)
			(property "ki_keywords" "0402, SMT, RESISTOR, PASSIVE"
				(at 0 0 0)
				(effects
					(font
						(size 1.27 1.27)
					)
					(hide yes)
				)
			)
			(symbol "R_4k7_0402_0_1"
				(rectangle
					(start 0.635 0.889)
					(end 4.445 -0.889)
					(stroke
						(width 0.254)
						(type default)
					)
					(fill
						(type none)
					)
				)
			)
			(symbol "R_4k7_0402_1_1"
				(pin passive line
					(at 0 0 0)
					(length 0.635)
					(name "~"
						(effects
							(font
								(size 1.27 1.27)
							)
						)
					)
					(number "1"
						(effects
							(font
								(size 1.27 1.27)
							)
						)
					)
				)
				(pin passive line
					(at 5.08 0 180)
					(length 0.635)
					(name "~"
						(effects
							(font
								(size 1.27 1.27)
							)
						)
					)
					(number "2"
						(effects
							(font
								(size 1.27 1.27)
							)
						)
					)
				)
			)
		)
	(symbol "antmicroResistors0402:R_6k8_0402"
			(pin_numbers
				(hide yes)
			)
			(pin_names
				(hide yes)
			)
			(exclude_from_sim no)
			(in_bom yes)
			(on_board yes)
			(property "Reference" "R"
				(at 20.32 -5.08 0)
				(effects
					(font
						(size 1.27 1.27)
						(thickness 0.15)
					)
					(justify left bottom)
				)
			)
			(property "Value" "R_6k8_0402"
				(at 20.32 -12.7 0)
				(effects
					(font
						(size 1.27 1.27)
						(thickness 0.15)
					)
					(justify left bottom)
					(hide yes)
				)
			)
			(property "Footprint" "antmicro-footprints:R_0402_1005Metric"
				(at 20.32 -15.24 0)
				(effects
					(font
						(size 1.27 1.27)
						(thickness 0.15)
					)
					(justify left bottom)
					(hide yes)
				)
			)
			(property "Datasheet" "https://www.bourns.com/docs/product-datasheets/cr.pdf"
				(at 20.32 -17.78 0)
				(effects
					(font
						(size 1.27 1.27)
						(thickness 0.15)
					)
					(justify left bottom)
					(hide yes)
				)
			)
			(property "Description" "SMD Chip Resistor, 6.8 kohm, ± 1%, 63 mW, 0402 [1005 Metric], Thick Film, General Purpose"
				(at 0 0 0)
				(effects
					(font
						(size 1.27 1.27)
					)
					(hide yes)
				)
			)
			(property "MPN" "CR0402-FX-6801GLF"
				(at 20.32 -20.32 0)
				(effects
					(font
						(size 1.27 1.27)
						(thickness 0.15)
					)
					(justify left bottom)
					(hide yes)
				)
			)
			(property "Manufacturer" "Bourns"
				(at 20.32 -22.86 0)
				(effects
					(font
						(size 1.27 1.27)
						(thickness 0.15)
					)
					(justify left bottom)
					(hide yes)
				)
			)
			(property "License" "Apache-2.0"
				(at 20.32 -25.4 0)
				(effects
					(font
						(size 1.27 1.27)
						(thickness 0.15)
					)
					(justify left bottom)
					(hide yes)
				)
			)
			(property "Author" "Antmicro"
				(at 20.32 -27.94 0)
				(effects
					(font
						(size 1.27 1.27)
						(thickness 0.15)
					)
					(justify left bottom)
					(hide yes)
				)
			)
			(property "Val" "6k8"
				(at 20.32 -7.62 0)
				(effects
					(font
						(size 1.27 1.27)
						(thickness 0.15)
					)
					(justify left bottom)
				)
			)
			(property "Tolerance" "1%"
				(at 20.32 -10.16 0)
				(effects
					(font
						(size 1.27 1.27)
					)
					(justify left bottom)
					(hide yes)
				)
			)
			(property "ki_keywords" "0402, SMT, RESISTOR, PASSIVE"
				(at 0 0 0)
				(effects
					(font
						(size 1.27 1.27)
					)
					(hide yes)
				)
			)
			(symbol "R_6k8_0402_0_1"
				(rectangle
					(start 0.635 0.889)
					(end 4.445 -0.889)
					(stroke
						(width 0.254)
						(type default)
					)
					(fill
						(type none)
					)
				)
			)
			(symbol "R_6k8_0402_1_1"
				(pin passive line
					(at 0 0 0)
					(length 0.635)
					(name "~"
						(effects
							(font
								(size 1.27 1.27)
							)
						)
					)
					(number "1"
						(effects
							(font
								(size 1.27 1.27)
							)
						)
					)
				)
				(pin passive line
					(at 5.08 0 180)
					(length 0.635)
					(name "~"
						(effects
							(font
								(size 1.27 1.27)
							)
						)
					)
					(number "2"
						(effects
							(font
								(size 1.27 1.27)
							)
						)
					)
				)
			)
		)
	(symbol "antmicroResistors0402:R_910k_0402"
			(pin_numbers
				(hide yes)
			)
			(pin_names
				(hide yes)
			)
			(exclude_from_sim no)
			(in_bom yes)
			(on_board yes)
			(property "Reference" "R"
				(at 20.32 -5.08 0)
				(effects
					(font
						(size 1.27 1.27)
						(thickness 0.15)
					)
					(justify left bottom)
				)
			)
			(property "Value" "R_910k_0402"
				(at 20.32 -12.7 0)
				(effects
					(font
						(size 1.27 1.27)
						(thickness 0.15)
					)
					(justify left bottom)
					(hide yes)
				)
			)
			(property "Footprint" "antmicro-footprints:R_0402_1005Metric"
				(at 20.32 -15.24 0)
				(effects
					(font
						(size 1.27 1.27)
						(thickness 0.15)
					)
					(justify left bottom)
					(hide yes)
				)
			)
			(property "Datasheet" "https://www.bourns.com/docs/product-datasheets/cr.pdf"
				(at 20.32 -17.78 0)
				(effects
					(font
						(size 1.27 1.27)
						(thickness 0.15)
					)
					(justify left bottom)
					(hide yes)
				)
			)
			(property "Description" "SMD Chip Resistor"
				(at 0 0 0)
				(effects
					(font
						(size 1.27 1.27)
					)
					(hide yes)
				)
			)
			(property "MPN" "CR0402-FX-9103GLF"
				(at 20.32 -20.32 0)
				(effects
					(font
						(size 1.27 1.27)
						(thickness 0.15)
					)
					(justify left bottom)
					(hide yes)
				)
			)
			(property "Manufacturer" "Bourns"
				(at 20.32 -22.86 0)
				(effects
					(font
						(size 1.27 1.27)
						(thickness 0.15)
					)
					(justify left bottom)
					(hide yes)
				)
			)
			(property "License" "Apache-2.0"
				(at 20.32 -25.4 0)
				(effects
					(font
						(size 1.27 1.27)
						(thickness 0.15)
					)
					(justify left bottom)
					(hide yes)
				)
			)
			(property "Author" "Antmicro"
				(at 20.32 -27.94 0)
				(effects
					(font
						(size 1.27 1.27)
						(thickness 0.15)
					)
					(justify left bottom)
					(hide yes)
				)
			)
			(property "Val" "910k"
				(at 20.32 -7.62 0)
				(effects
					(font
						(size 1.27 1.27)
						(thickness 0.15)
					)
					(justify left bottom)
				)
			)
			(property "Tolerance" "1%"
				(at 20.32 -10.16 0)
				(effects
					(font
						(size 1.27 1.27)
					)
					(justify left bottom)
					(hide yes)
				)
			)
			(property "ki_keywords" "0402, SMT, RESISTOR, PASSIVE"
				(at 0 0 0)
				(effects
					(font
						(size 1.27 1.27)
					)
					(hide yes)
				)
			)
			(symbol "R_910k_0402_0_1"
				(rectangle
					(start 0.635 0.889)
					(end 4.445 -0.889)
					(stroke
						(width 0.254)
						(type default)
					)
					(fill
						(type none)
					)
				)
			)
			(symbol "R_910k_0402_1_1"
				(pin passive line
					(at 0 0 0)
					(length 0.635)
					(name "~"
						(effects
							(font
								(size 1.27 1.27)
							)
						)
					)
					(number "1"
						(effects
							(font
								(size 1.27 1.27)
							)
						)
					)
				)
				(pin passive line
					(at 5.08 0 180)
					(length 0.635)
					(name "~"
						(effects
							(font
								(size 1.27 1.27)
							)
						)
					)
					(number "2"
						(effects
							(font
								(size 1.27 1.27)
							)
						)
					)
				)
			)
		)
	(symbol "antmicroResistors0603:R_0R_22.4A_0603"
			(pin_numbers
				(hide yes)
			)
			(pin_names
				(hide yes)
			)
			(exclude_from_sim no)
			(in_bom yes)
			(on_board yes)
			(property "Reference" "R"
				(at 15.24 -2.54 0)
				(effects
					(font
						(size 1.27 1.27)
						(thickness 0.15)
					)
					(justify left bottom)
				)
			)
			(property "Value" "R_0R_22.4A_0603"
				(at 15.24 -5.08 0)
				(effects
					(font
						(size 1.27 1.27)
						(thickness 0.15)
					)
					(justify left bottom)
					(hide yes)
				)
			)
			(property "Footprint" "antmicro-footprints:R_0603_1608Metric"
				(at 15.24 -10.16 0)
				(effects
					(font
						(size 1.27 1.27)
						(thickness 0.15)
					)
					(justify left bottom)
					(hide yes)
				)
			)
			(property "Datasheet" "https://fscdn.rohm.com/en/products/databook/datasheet/passive/resistor/chip_resistor/pmr-jpw-e.pdf"
				(at 15.24 -12.7 0)
				(effects
					(font
						(size 1.27 1.27)
						(thickness 0.15)
					)
					(justify left bottom)
					(hide yes)
				)
			)
			(property "Description" "SMD Chip Resistor"
				(at 0 0 0)
				(effects
					(font
						(size 1.27 1.27)
					)
					(hide yes)
				)
			)
			(property "MPN" "PMR03EZPJ000"
				(at 15.24 -15.24 0)
				(effects
					(font
						(size 1.27 1.27)
						(thickness 0.15)
					)
					(justify left bottom)
					(hide yes)
				)
			)
			(property "Manufacturer" "ROHM Semiconductor"
				(at 15.24 -17.78 0)
				(effects
					(font
						(size 1.27 1.27)
						(thickness 0.15)
					)
					(justify left bottom)
					(hide yes)
				)
			)
			(property "Val" "0R"
				(at 15.24 -7.62 0)
				(effects
					(font
						(size 1.27 1.27)
						(thickness 0.15)
					)
					(justify left bottom)
				)
			)
			(property "Max. Curr." "22.4A"
				(at 15.24 -20.32 0)
				(effects
					(font
						(size 1.27 1.27)
						(thickness 0.15)
					)
					(justify left bottom)
				)
			)
			(property "Author" "Antmicro"
				(at 15.24 -22.86 0)
				(effects
					(font
						(size 1.27 1.27)
						(thickness 0.15)
					)
					(justify left bottom)
					(hide yes)
				)
			)
			(property "License" "Apache-2.0"
				(at 15.24 -25.4 0)
				(effects
					(font
						(size 1.27 1.27)
						(thickness 0.15)
					)
					(justify left bottom)
					(hide yes)
				)
			)
			(property "Tolerance" "template_tolerance"
				(at 20.32 -10.16 0)
				(effects
					(font
						(size 1.27 1.27)
					)
					(justify left bottom)
					(hide yes)
				)
			)
			(property "ki_keywords" "0603, SMT, RESISTOR, PASSIVE"
				(at 0 0 0)
				(effects
					(font
						(size 1.27 1.27)
					)
					(hide yes)
				)
			)
			(symbol "R_0R_22.4A_0603_0_1"
				(rectangle
					(start 0.635 0.889)
					(end 4.445 -0.889)
					(stroke
						(width 0.254)
						(type default)
					)
					(fill
						(type none)
					)
				)
			)
			(symbol "R_0R_22.4A_0603_1_1"
				(pin passive line
					(at 0 0 0)
					(length 0.635)
					(name "~"
						(effects
							(font
								(size 1.27 1.27)
							)
						)
					)
					(number "1"
						(effects
							(font
								(size 1.27 1.27)
							)
						)
					)
				)
				(pin passive line
					(at 5.08 0 180)
					(length 0.635)
					(name "~"
						(effects
							(font
								(size 1.27 1.27)
							)
						)
					)
					(number "2"
						(effects
							(font
								(size 1.27 1.27)
							)
						)
					)
				)
			)
		)
	(symbol "antmicroResistors0603:R_63R4_0603"
			(pin_numbers
				(hide yes)
			)
			(pin_names
				(hide yes)
			)
			(exclude_from_sim no)
			(in_bom yes)
			(on_board yes)
			(property "Reference" "R"
				(at 20.32 -5.08 0)
				(effects
					(font
						(size 1.27 1.27)
						(thickness 0.15)
					)
					(justify left bottom)
				)
			)
			(property "Value" "R_63R4_0603"
				(at 20.32 -12.7 0)
				(effects
					(font
						(size 1.27 1.27)
						(thickness 0.15)
					)
					(justify left bottom)
					(hide yes)
				)
			)
			(property "Footprint" "antmicro-footprints:R_0603_1608Metric"
				(at 20.32 -15.24 0)
				(effects
					(font
						(size 1.27 1.27)
						(thickness 0.15)
					)
					(justify left bottom)
					(hide yes)
				)
			)
			(property "Datasheet" "https://www.bourns.com/docs/product-datasheets/cr.pdf"
				(at 20.32 -17.78 0)
				(effects
					(font
						(size 1.27 1.27)
						(thickness 0.15)
					)
					(justify left bottom)
					(hide yes)
				)
			)
			(property "Description" "SMD Chip Resistor"
				(at 0 0 0)
				(effects
					(font
						(size 1.27 1.27)
					)
					(hide yes)
				)
			)
			(property "MPN" "CR0603-FX-63R4ELF"
				(at 20.32 -20.32 0)
				(effects
					(font
						(size 1.27 1.27)
						(thickness 0.15)
					)
					(justify left bottom)
					(hide yes)
				)
			)
			(property "Manufacturer" "Bourns"
				(at 20.32 -22.86 0)
				(effects
					(font
						(size 1.27 1.27)
						(thickness 0.15)
					)
					(justify left bottom)
					(hide yes)
				)
			)
			(property "License" "Apache-2.0"
				(at 20.32 -25.4 0)
				(effects
					(font
						(size 1.27 1.27)
						(thickness 0.15)
					)
					(justify left bottom)
					(hide yes)
				)
			)
			(property "Author" "Antmicro"
				(at 20.32 -27.94 0)
				(effects
					(font
						(size 1.27 1.27)
						(thickness 0.15)
					)
					(justify left bottom)
					(hide yes)
				)
			)
			(property "Val" "63R4"
				(at 20.32 -7.62 0)
				(effects
					(font
						(size 1.27 1.27)
						(thickness 0.15)
					)
					(justify left bottom)
				)
			)
			(property "Tolerance" "1%"
				(at 20.32 -10.16 0)
				(effects
					(font
						(size 1.27 1.27)
					)
					(justify left bottom)
					(hide yes)
				)
			)
			(property "ki_keywords" "0603, SMT, RESISTOR, PASSIVE"
				(at 0 0 0)
				(effects
					(font
						(size 1.27 1.27)
					)
					(hide yes)
				)
			)
			(symbol "R_63R4_0603_0_1"
				(rectangle
					(start 0.635 0.889)
					(end 4.445 -0.889)
					(stroke
						(width 0.254)
						(type default)
					)
					(fill
						(type none)
					)
				)
			)
			(symbol "R_63R4_0603_1_1"
				(pin passive line
					(at 0 0 0)
					(length 0.635)
					(name "~"
						(effects
							(font
								(size 1.27 1.27)
							)
						)
					)
					(number "1"
						(effects
							(font
								(size 1.27 1.27)
							)
						)
					)
				)
				(pin passive line
					(at 5.08 0 180)
					(length 0.635)
					(name "~"
						(effects
							(font
								(size 1.27 1.27)
							)
						)
					)
					(number "2"
						(effects
							(font
								(size 1.27 1.27)
							)
						)
					)
				)
			)
		)
	(symbol "antmicroResonators:Resonator_12MHz_ABM8G"
			(pin_names
				(hide yes)
			)
			(exclude_from_sim no)
			(in_bom yes)
			(on_board yes)
			(property "Reference" "Y"
				(at 15.24 -5.08 0)
				(effects
					(font
						(size 1.27 1.27)
						(thickness 0.15)
					)
					(justify left bottom)
				)
			)
			(property "Value" "Resonator_12MHz_ABM8G"
				(at 15.24 -12.7 0)
				(effects
					(font
						(size 1.27 1.27)
						(thickness 0.15)
					)
					(justify left bottom)
					(hide yes)
				)
			)
			(property "Footprint" "antmicro-footprints:Resonator_SMD_Abracon_ABM8G_3.2x2.5mm"
				(at 15.24 -15.24 0)
				(effects
					(font
						(size 1.27 1.27)
						(thickness 0.15)
					)
					(justify left bottom)
					(hide yes)
				)
			)
			(property "Datasheet" "https://abracon.com/Resonators/ABM8G.pdf"
				(at 15.24 -17.78 0)
				(effects
					(font
						(size 1.27 1.27)
						(thickness 0.15)
					)
					(justify left bottom)
					(hide yes)
				)
			)
			(property "Description" "Crystal, 12 MHz, SMT, 3.2mm x 2.5mm, 30 ppm, 18 pF, 20 ppm, ABM8G"
				(at 0 0 0)
				(effects
					(font
						(size 1.27 1.27)
					)
					(hide yes)
				)
			)
			(property "MPN" "ABM8G-12.000MHZ-18-D2Y-T"
				(at 15.24 -7.62 0)
				(effects
					(font
						(size 1.27 1.27)
						(thickness 0.15)
					)
					(justify left bottom)
				)
			)
			(property "Manufacturer" "Abracon"
				(at 15.24 -20.32 0)
				(effects
					(font
						(size 1.27 1.27)
						(thickness 0.15)
					)
					(justify left bottom)
					(hide yes)
				)
			)
			(property "Author" "Antmicro"
				(at 15.24 -22.86 0)
				(effects
					(font
						(size 1.27 1.27)
						(thickness 0.15)
					)
					(justify left bottom)
					(hide yes)
				)
			)
			(property "License" "Apache-2.0"
				(at 15.24 -25.4 0)
				(effects
					(font
						(size 1.27 1.27)
						(thickness 0.15)
					)
					(justify left bottom)
					(hide yes)
				)
			)
			(property "Val" "12 MHz"
				(at 15.24 -10.16 0)
				(effects
					(font
						(size 1.27 1.27)
						(thickness 0.15)
					)
					(justify left bottom)
				)
			)
			(property "ki_keywords" "SMT, CERAMIC, OSCILLATOR"
				(at 0 0 0)
				(effects
					(font
						(size 1.27 1.27)
					)
					(hide yes)
				)
			)
			(symbol "Resonator_12MHz_ABM8G_1_1"
				(polyline
					(pts
						(xy 1.905 1.905) (xy 1.905 2.54) (xy 5.715 2.54) (xy 5.715 1.905)
					)
					(stroke
						(width 0.254)
						(type default)
					)
					(fill
						(type none)
					)
				)
				(polyline
					(pts
						(xy 1.905 -1.905) (xy 1.905 -2.54) (xy 5.715 -2.54) (xy 5.715 -1.905)
					)
					(stroke
						(width 0.254)
						(type default)
					)
					(fill
						(type none)
					)
				)
				(polyline
					(pts
						(xy 2.54 1.27) (xy 2.54 -1.27)
					)
					(stroke
						(width 0.254)
						(type default)
					)
					(fill
						(type background)
					)
				)
				(rectangle
					(start 3.175 1.905)
					(end 4.445 -1.905)
					(stroke
						(width 0.254)
						(type default)
					)
					(fill
						(type background)
					)
				)
				(polyline
					(pts
						(xy 5.08 1.27) (xy 5.08 -1.27)
					)
					(stroke
						(width 0.254)
						(type default)
					)
					(fill
						(type background)
					)
				)
				(pin passive line
					(at 0 0 0)
					(length 2.54)
					(name "~"
						(effects
							(font
								(size 1.27 1.27)
							)
						)
					)
					(number "1"
						(effects
							(font
								(size 1.27 1.27)
							)
						)
					)
				)
				(pin passive line
					(at 3.81 -5.08 90)
					(length 2.54)
					(name "SH"
						(effects
							(font
								(size 1.27 1.27)
							)
						)
					)
					(number "2"
						(effects
							(font
								(size 1.27 1.27)
							)
						)
					)
				)
				(pin passive line
					(at 3.81 -5.08 90)
					(length 2.54)
					(hide yes)
					(name "SH"
						(effects
							(font
								(size 1.27 1.27)
							)
						)
					)
					(number "4"
						(effects
							(font
								(size 1.27 1.27)
							)
						)
					)
				)
				(pin passive line
					(at 7.62 0 180)
					(length 2.54)
					(name "~"
						(effects
							(font
								(size 1.27 1.27)
							)
						)
					)
					(number "3"
						(effects
							(font
								(size 1.27 1.27)
							)
						)
					)
				)
			)
		)
	(symbol "antmicroResonators:Resonator_27.12MHz_XRCGB"
			(pin_names
				(hide yes)
			)
			(exclude_from_sim no)
			(in_bom yes)
			(on_board yes)
			(property "Reference" "Y"
				(at 22.86 -2.54 0)
				(effects
					(font
						(size 1.27 1.27)
						(thickness 0.15)
					)
					(justify left bottom)
				)
			)
			(property "Value" "Resonator_27.12MHz_XRCGB"
				(at 22.86 -7.62 0)
				(effects
					(font
						(size 1.27 1.27)
						(thickness 0.15)
					)
					(justify left bottom)
					(hide yes)
				)
			)
			(property "Footprint" "antmicro-footprints:Resonator_SMD_Murata_XRCGB_2x1.6x0.65mm"
				(at 22.86 -10.16 0)
				(effects
					(font
						(size 1.27 1.27)
						(thickness 0.15)
					)
					(justify left bottom)
					(hide yes)
				)
			)
			(property "Datasheet" "https://www.murata.com/products/productdata/8801078247454/SPEC-XRCGB27M120F3M13R0.pdf?1541043011000"
				(at 22.86 -12.7 0)
				(effects
					(font
						(size 1.27 1.27)
						(thickness 0.15)
					)
					(justify left bottom)
					(hide yes)
				)
			)
			(property "Description" "Crystals 2.0x1.6x0.65mm 27.12MHz Crystal +/-30ppm Initial tolerance; CLoad: 10pF"
				(at 0 0 0)
				(effects
					(font
						(size 1.27 1.27)
					)
					(hide yes)
				)
			)
			(property "Manufacturer" "Murata"
				(at 22.86 -25.4 0)
				(effects
					(font
						(size 1.27 1.27)
					)
					(justify left bottom)
					(hide yes)
				)
			)
			(property "MPN" "XRCGB27M120F3M13R0"
				(at 22.86 -22.86 0)
				(effects
					(font
						(size 1.27 1.27)
					)
					(justify left bottom)
				)
			)
			(property "Val" "27.12MHz"
				(at 22.86 -5.08 0)
				(effects
					(font
						(size 1.27 1.27)
					)
					(justify left bottom)
				)
			)
			(property "CLoad" "10pF"
				(at 22.86 -20.32 0)
				(effects
					(font
						(size 1.27 1.27)
					)
					(justify left bottom)
					(hide yes)
				)
			)
			(property "Author" "Antmicro"
				(at 22.86 -15.24 0)
				(effects
					(font
						(size 1.27 1.27)
					)
					(justify left bottom)
					(hide yes)
				)
			)
			(property "License" "Apache-2.0"
				(at 22.86 -17.78 0)
				(effects
					(font
						(size 1.27 1.27)
					)
					(justify left bottom)
					(hide yes)
				)
			)
			(property "ki_keywords" "OSCILLATOR"
				(at 0 0 0)
				(effects
					(font
						(size 1.27 1.27)
					)
					(hide yes)
				)
			)
			(symbol "Resonator_27.12MHz_XRCGB_1_1"
				(polyline
					(pts
						(xy 1.905 1.905) (xy 1.905 2.54) (xy 5.715 2.54) (xy 5.715 1.905)
					)
					(stroke
						(width 0.254)
						(type default)
					)
					(fill
						(type none)
					)
				)
				(polyline
					(pts
						(xy 1.905 -1.905) (xy 1.905 -2.54) (xy 5.715 -2.54) (xy 5.715 -1.905)
					)
					(stroke
						(width 0.254)
						(type default)
					)
					(fill
						(type none)
					)
				)
				(polyline
					(pts
						(xy 2.54 1.27) (xy 2.54 -1.27)
					)
					(stroke
						(width 0.254)
						(type default)
					)
					(fill
						(type background)
					)
				)
				(rectangle
					(start 3.175 1.905)
					(end 4.445 -1.905)
					(stroke
						(width 0.254)
						(type default)
					)
					(fill
						(type background)
					)
				)
				(polyline
					(pts
						(xy 5.08 1.27) (xy 5.08 -1.27)
					)
					(stroke
						(width 0.254)
						(type default)
					)
					(fill
						(type background)
					)
				)
				(pin passive line
					(at 0 0 0)
					(length 2.54)
					(name "~"
						(effects
							(font
								(size 1.27 1.27)
							)
						)
					)
					(number "1"
						(effects
							(font
								(size 1.27 1.27)
							)
						)
					)
				)
				(pin passive line
					(at 3.81 -5.08 90)
					(length 2.54)
					(name "SH"
						(effects
							(font
								(size 1.27 1.27)
							)
						)
					)
					(number "2"
						(effects
							(font
								(size 1.27 1.27)
							)
						)
					)
				)
				(pin passive line
					(at 3.81 -5.08 90)
					(length 2.54)
					(hide yes)
					(name "SH"
						(effects
							(font
								(size 1.27 1.27)
							)
						)
					)
					(number "4"
						(effects
							(font
								(size 1.27 1.27)
							)
						)
					)
				)
				(pin passive line
					(at 7.62 0 180)
					(length 2.54)
					(name "~"
						(effects
							(font
								(size 1.27 1.27)
							)
						)
					)
					(number "3"
						(effects
							(font
								(size 1.27 1.27)
							)
						)
					)
				)
			)
		)
	(symbol "antmicroResonators:Resonator_32.768kHz_CM7V-T1A"
			(pin_names
				(hide yes)
			)
			(exclude_from_sim no)
			(in_bom yes)
			(on_board yes)
			(property "Reference" "Y"
				(at 15.24 -5.08 0)
				(effects
					(font
						(size 1.27 1.27)
						(thickness 0.15)
					)
					(justify left bottom)
				)
			)
			(property "Value" "Resonator_32.768kHz_CM7V-T1A"
				(at 15.24 -10.16 0)
				(effects
					(font
						(size 1.27 1.27)
						(thickness 0.15)
					)
					(justify left bottom)
					(hide yes)
				)
			)
			(property "Footprint" "antmicro-footprints:Resonator_SMD_MicroCrystal_CM7V-T1A_3.2x1.5x0.65mm"
				(at 15.24 -12.7 0)
				(effects
					(font
						(size 1.27 1.27)
						(thickness 0.15)
					)
					(justify left bottom)
					(hide yes)
				)
			)
			(property "Datasheet" "https://www.microcrystal.com/fileadmin/Media/Products/32kHz/Datasheet/CM7V-T1A.pdf"
				(at 15.24 -15.24 0)
				(effects
					(font
						(size 1.27 1.27)
						(thickness 0.15)
					)
					(justify left bottom)
					(hide yes)
				)
			)
			(property "Description" "Crystal, 32.768 kHz, SMD, 3.2mm x 1.5mm, 12.5 pF, 20 ppm, CC7V-T1A"
				(at 15.24 -30.48 0)
				(effects
					(font
						(size 1.27 1.27)
						(thickness 0.15)
					)
					(justify left bottom)
					(hide yes)
				)
			)
			(property "MPN" "CM7V-T1A-32.768kHz-12.5pF-20PPM-TC-QA"
				(at 15.24 -20.32 0)
				(effects
					(font
						(size 1.27 1.27)
						(thickness 0.15)
					)
					(justify left bottom)
					(hide yes)
				)
			)
			(property "Manufacturer" "Micro Crystal"
				(at 15.24 -22.86 0)
				(effects
					(font
						(size 1.27 1.27)
						(thickness 0.15)
					)
					(justify left bottom)
					(hide yes)
				)
			)
			(property "Val" "32.768 kHz"
				(at 15.24 -7.62 0)
				(effects
					(font
						(size 1.27 1.27)
						(thickness 0.15)
					)
					(justify left bottom)
				)
			)
			(property "Author" "Antmicro"
				(at 15.24 -25.4 0)
				(effects
					(font
						(size 1.27 1.27)
						(thickness 0.15)
					)
					(justify left bottom)
					(hide yes)
				)
			)
			(property "License" "Apache-2.0"
				(at 15.24 -27.94 0)
				(effects
					(font
						(size 1.27 1.27)
						(thickness 0.15)
					)
					(justify left bottom)
					(hide yes)
				)
			)
			(property "ki_keywords" "SMT, OSCILLATOR"
				(at 0 0 0)
				(effects
					(font
						(size 1.27 1.27)
					)
					(hide yes)
				)
			)
			(symbol "Resonator_32.768kHz_CM7V-T1A_1_1"
				(polyline
					(pts
						(xy 2.54 1.27) (xy 2.54 -1.27)
					)
					(stroke
						(width 0.254)
						(type default)
					)
					(fill
						(type background)
					)
				)
				(rectangle
					(start 3.175 1.905)
					(end 4.445 -1.905)
					(stroke
						(width 0.254)
						(type default)
					)
					(fill
						(type background)
					)
				)
				(polyline
					(pts
						(xy 5.08 1.27) (xy 5.08 -1.27)
					)
					(stroke
						(width 0.254)
						(type default)
					)
					(fill
						(type background)
					)
				)
				(pin passive line
					(at 0 0 0)
					(length 2.54)
					(name "~"
						(effects
							(font
								(size 1.27 1.27)
							)
						)
					)
					(number "1"
						(effects
							(font
								(size 1.27 1.27)
							)
						)
					)
				)
				(pin passive line
					(at 7.62 0 180)
					(length 2.54)
					(name "~"
						(effects
							(font
								(size 1.27 1.27)
							)
						)
					)
					(number "2"
						(effects
							(font
								(size 1.27 1.27)
							)
						)
					)
				)
			)
		)
	(symbol "antmicroSlideSwitches:CAS-120TA"
			(pin_names
				(hide yes)
			)
			(exclude_from_sim no)
			(in_bom yes)
			(on_board yes)
			(property "Reference" "SW"
				(at 25.4 -2.54 0)
				(effects
					(font
						(size 1.27 1.27)
						(thickness 0.15)
					)
					(justify left bottom)
				)
			)
			(property "Value" "CAS-120TA"
				(at 25.4 -5.08 0)
				(effects
					(font
						(size 1.27 1.27)
						(thickness 0.15)
					)
					(justify left bottom)
				)
			)
			(property "Footprint" "antmicro-footprints:Switch_Slide_CAS-120TA"
				(at 25.4 -7.62 0)
				(effects
					(font
						(size 1.27 1.27)
						(thickness 0.15)
					)
					(justify left bottom)
					(hide yes)
				)
			)
			(property "Datasheet" "https://www.nidec-components.com/e/catalog/switch/cas.pdf"
				(at 25.4 -10.16 0)
				(effects
					(font
						(size 1.27 1.27)
						(thickness 0.15)
					)
					(justify left bottom)
					(hide yes)
				)
			)
			(property "Description" "Slide switch"
				(at 0 0 0)
				(effects
					(font
						(size 1.27 1.27)
					)
					(hide yes)
				)
			)
			(property "MPN" "CAS-120TA"
				(at 25.4 -12.7 0)
				(effects
					(font
						(size 1.27 1.27)
						(thickness 0.15)
					)
					(justify left bottom)
					(hide yes)
				)
			)
			(property "Manufacturer" "Nidec Components"
				(at 25.4 -15.24 0)
				(effects
					(font
						(size 1.27 1.27)
						(thickness 0.15)
					)
					(justify left bottom)
					(hide yes)
				)
			)
			(property "Author" "Antmicro"
				(at 25.4 -17.78 0)
				(effects
					(font
						(size 1.27 1.27)
						(thickness 0.15)
					)
					(justify left bottom)
					(hide yes)
				)
			)
			(property "License" "Apache-2.0"
				(at 25.4 -20.32 0)
				(effects
					(font
						(size 1.27 1.27)
						(thickness 0.15)
					)
					(justify left bottom)
					(hide yes)
				)
			)
			(property "ki_keywords" "MECHANICAL"
				(at 0 0 0)
				(effects
					(font
						(size 1.27 1.27)
					)
					(hide yes)
				)
			)
			(symbol "CAS-120TA_1_1"
				(rectangle
					(start 2.54 3.81)
					(end 10.16 -3.81)
					(stroke
						(width 0)
						(type default)
					)
					(fill
						(type background)
					)
				)
				(polyline
					(pts
						(xy 3.81 0) (xy 2.54 0)
					)
					(stroke
						(width 0.254)
						(type default)
					)
					(fill
						(type none)
					)
				)
				(circle
					(center 4.064 0)
					(radius 0.3556)
					(stroke
						(width 0.254)
						(type default)
					)
					(fill
						(type outline)
					)
				)
				(polyline
					(pts
						(xy 4.318 0) (xy 9.398 2.286)
					)
					(stroke
						(width 0.254)
						(type default)
					)
					(fill
						(type background)
					)
				)
				(circle
					(center 8.636 -2.54)
					(radius 0.3556)
					(stroke
						(width 0.254)
						(type default)
					)
					(fill
						(type outline)
					)
				)
				(circle
					(center 8.89 2.54)
					(radius 0.3556)
					(stroke
						(width 0.254)
						(type default)
					)
					(fill
						(type outline)
					)
				)
				(polyline
					(pts
						(xy 10.16 2.54) (xy 8.89 2.54)
					)
					(stroke
						(width 0.254)
						(type default)
					)
					(fill
						(type none)
					)
				)
				(polyline
					(pts
						(xy 10.16 -2.54) (xy 8.89 -2.54)
					)
					(stroke
						(width 0.254)
						(type default)
					)
					(fill
						(type none)
					)
				)
				(pin passive line
					(at 0 0 0)
					(length 2.54)
					(name "~"
						(effects
							(font
								(size 1.27 1.27)
							)
						)
					)
					(number "2"
						(effects
							(font
								(size 1.27 1.27)
							)
						)
					)
				)
				(pin passive line
					(at 12.7 2.54 180)
					(length 2.54)
					(name "~"
						(effects
							(font
								(size 1.27 1.27)
							)
						)
					)
					(number "1"
						(effects
							(font
								(size 1.27 1.27)
							)
						)
					)
				)
				(pin passive line
					(at 12.7 -2.54 180)
					(length 2.54)
					(name "~"
						(effects
							(font
								(size 1.27 1.27)
							)
						)
					)
					(number "3"
						(effects
							(font
								(size 1.27 1.27)
							)
						)
					)
				)
			)
		)
	(symbol "antmicroTVSDiodes:PESD5Z5_0F"
			(pin_numbers
				(hide yes)
			)
			(pin_names
				(hide yes)
			)
			(exclude_from_sim no)
			(in_bom yes)
			(on_board yes)
			(property "Reference" "D"
				(at 15.24 0 0)
				(effects
					(font
						(size 1.27 1.27)
						(thickness 0.15)
					)
					(justify left bottom)
				)
			)
			(property "Value" "PESD5Z5_0F"
				(at 15.24 -12.7 0)
				(effects
					(font
						(size 1.27 1.27)
						(thickness 0.15)
					)
					(justify left bottom)
					(hide yes)
				)
			)
			(property "Footprint" "antmicro-footprints:SOD-523"
				(at 15.24 -5.08 0)
				(effects
					(font
						(size 1.27 1.27)
						(thickness 0.15)
					)
					(justify left bottom)
					(hide yes)
				)
			)
			(property "Datasheet" "https://assets.nexperia.com/documents/data-sheet/PESD5Z5_0.pdf"
				(at 15.24 -7.62 0)
				(effects
					(font
						(size 1.27 1.27)
						(thickness 0.15)
					)
					(justify left bottom)
					(hide yes)
				)
			)
			(property "Description" "Unidirectional TVS, 30 kV,  SOD-523, 5 V, 89 pF"
				(at 0 0 0)
				(effects
					(font
						(size 1.27 1.27)
					)
					(hide yes)
				)
			)
			(property "Manufacturer" "Nexperia"
				(at 15.24 -10.16 0)
				(effects
					(font
						(size 1.27 1.27)
						(thickness 0.15)
					)
					(justify left bottom)
					(hide yes)
				)
			)
			(property "MPN" "PESD5Z5.0F"
				(at 15.24 -2.54 0)
				(effects
					(font
						(size 1.27 1.27)
						(thickness 0.15)
					)
					(justify left bottom)
				)
			)
			(property "Author" "Antmicro"
				(at 15.24 -15.24 0)
				(effects
					(font
						(size 1.27 1.27)
						(thickness 0.15)
					)
					(justify left bottom)
					(hide yes)
				)
			)
			(property "License" "Apache-2.0"
				(at 15.24 -17.78 0)
				(effects
					(font
						(size 1.27 1.27)
						(thickness 0.15)
					)
					(justify left bottom)
					(hide yes)
				)
			)
			(property "ki_keywords" "DIODE, SEMICONDUCTOR, TVS, ESD"
				(at 0 0 0)
				(effects
					(font
						(size 1.27 1.27)
					)
					(hide yes)
				)
			)
			(symbol "PESD5Z5_0F_0_1"
				(polyline
					(pts
						(xy 1.905 0) (xy 0.635 0)
					)
					(stroke
						(width 0)
						(type default)
					)
					(fill
						(type none)
					)
				)
				(polyline
					(pts
						(xy 4.445 0) (xy 3.175 0)
					)
					(stroke
						(width 0)
						(type default)
					)
					(fill
						(type none)
					)
				)
			)
			(symbol "PESD5Z5_0F_1_1"
				(polyline
					(pts
						(xy 1.778 1.016) (xy 1.397 1.016)
					)
					(stroke
						(width 0.254)
						(type default)
					)
					(fill
						(type none)
					)
				)
				(polyline
					(pts
						(xy 1.778 1.016) (xy 1.778 -1.016)
					)
					(stroke
						(width 0.254)
						(type default)
					)
					(fill
						(type none)
					)
				)
				(polyline
					(pts
						(xy 2.159 -1.016) (xy 1.778 -1.016)
					)
					(stroke
						(width 0.254)
						(type default)
					)
					(fill
						(type none)
					)
				)
				(polyline
					(pts
						(xy 3.302 1.016) (xy 3.302 -1.016) (xy 1.778 0) (xy 3.302 1.016)
					)
					(stroke
						(width 0.254)
						(type default)
					)
					(fill
						(type outline)
					)
				)
				(pin passive line
					(at 0 0 0)
					(length 0.635)
					(name "C"
						(effects
							(font
								(size 1.27 1.27)
							)
						)
					)
					(number "1"
						(effects
							(font
								(size 1.27 1.27)
							)
						)
					)
				)
				(pin passive line
					(at 5.08 0 180)
					(length 0.635)
					(name "A"
						(effects
							(font
								(size 1.27 1.27)
							)
						)
					)
					(number "2"
						(effects
							(font
								(size 1.27 1.27)
							)
						)
					)
				)
			)
		)
	(symbol "antmicroTVSDiodes:PTVS58VS1UR,115"
			(pin_numbers
				(hide yes)
			)
			(pin_names
				(hide yes)
			)
			(exclude_from_sim no)
			(in_bom yes)
			(on_board yes)
			(property "Reference" "D"
				(at 21.59 -5.08 0)
				(effects
					(font
						(size 1.27 1.27)
						(thickness 0.15)
					)
					(justify left bottom)
				)
			)
			(property "Value" "PTVS58VS1UR,115"
				(at 21.59 -15.24 0)
				(effects
					(font
						(size 1.27 1.27)
						(thickness 0.15)
					)
					(justify left bottom)
					(hide yes)
				)
			)
			(property "Footprint" "antmicro-footprints:D_SOD-123F"
				(at 21.59 -10.16 0)
				(effects
					(font
						(size 1.27 1.27)
						(thickness 0.15)
					)
					(justify left bottom)
					(hide yes)
				)
			)
			(property "Datasheet" "https://assets.nexperia.com/documents/data-sheet/PTVSXS1UR_SER.pdf"
				(at 21.59 -12.7 0)
				(effects
					(font
						(size 1.27 1.27)
						(thickness 0.15)
					)
					(justify left bottom)
					(hide yes)
				)
			)
			(property "Description" "Unidirectional TVS, 8 kV,  SOD-123F, 58 V"
				(at 0 0 0)
				(effects
					(font
						(size 1.27 1.27)
					)
					(hide yes)
				)
			)
			(property "MPN" "PTVS58VS1UR,115"
				(at 21.59 -7.62 0)
				(effects
					(font
						(size 1.27 1.27)
						(thickness 0.15)
					)
					(justify left bottom)
				)
			)
			(property "Manufacturer" "Nexperia"
				(at 21.59 -17.78 0)
				(effects
					(font
						(size 1.27 1.27)
						(thickness 0.15)
					)
					(justify left bottom)
					(hide yes)
				)
			)
			(property "Author" "Antmicro"
				(at 21.59 -20.32 0)
				(effects
					(font
						(size 1.27 1.27)
						(thickness 0.15)
					)
					(justify left bottom)
					(hide yes)
				)
			)
			(property "License" "Apache-2.0"
				(at 21.59 -22.86 0)
				(effects
					(font
						(size 1.27 1.27)
						(thickness 0.15)
					)
					(justify left bottom)
					(hide yes)
				)
			)
			(property "ki_keywords" "DIODE, SEMICONDUCTOR, TVS, ESD"
				(at 0 0 0)
				(effects
					(font
						(size 1.27 1.27)
					)
					(hide yes)
				)
			)
			(symbol "PTVS58VS1UR,115_0_1"
				(polyline
					(pts
						(xy 1.905 0) (xy 0.635 0)
					)
					(stroke
						(width 0)
						(type default)
					)
					(fill
						(type none)
					)
				)
				(polyline
					(pts
						(xy 4.445 0) (xy 3.175 0)
					)
					(stroke
						(width 0)
						(type default)
					)
					(fill
						(type none)
					)
				)
			)
			(symbol "PTVS58VS1UR,115_1_1"
				(polyline
					(pts
						(xy 1.778 1.016) (xy 1.397 1.016)
					)
					(stroke
						(width 0.254)
						(type default)
					)
					(fill
						(type none)
					)
				)
				(polyline
					(pts
						(xy 1.778 1.016) (xy 1.778 -1.016)
					)
					(stroke
						(width 0.254)
						(type default)
					)
					(fill
						(type none)
					)
				)
				(polyline
					(pts
						(xy 2.159 -1.016) (xy 1.778 -1.016)
					)
					(stroke
						(width 0.254)
						(type default)
					)
					(fill
						(type none)
					)
				)
				(polyline
					(pts
						(xy 3.302 1.016) (xy 3.302 -1.016) (xy 1.778 0) (xy 3.302 1.016)
					)
					(stroke
						(width 0.254)
						(type default)
					)
					(fill
						(type outline)
					)
				)
				(pin passive line
					(at 0 0 0)
					(length 0.635)
					(name "C"
						(effects
							(font
								(size 1.27 1.27)
							)
						)
					)
					(number "1"
						(effects
							(font
								(size 1.27 1.27)
							)
						)
					)
				)
				(pin passive line
					(at 5.08 0 180)
					(length 0.635)
					(name "A"
						(effects
							(font
								(size 1.27 1.27)
							)
						)
					)
					(number "2"
						(effects
							(font
								(size 1.27 1.27)
							)
						)
					)
				)
			)
		)
	(symbol "antmicroTVSDiodes:PUSB3F96X_PASS"
			(exclude_from_sim no)
			(in_bom yes)
			(on_board yes)
			(property "Reference" "D"
				(at 25.4 -2.54 0)
				(effects
					(font
						(size 1.27 1.27)
						(thickness 0.15)
					)
					(justify left bottom)
				)
			)
			(property "Value" "PUSB3F96X_PASS"
				(at 25.4 -7.62 0)
				(effects
					(font
						(size 1.27 1.27)
						(thickness 0.15)
					)
					(justify left bottom)
					(hide yes)
				)
			)
			(property "Footprint" "antmicro-footprints:Nexperia_DFN-10_2.5x1mm_P0.5mm"
				(at 25.4 -10.16 0)
				(effects
					(font
						(size 1.27 1.27)
						(thickness 0.15)
					)
					(justify left bottom)
					(hide yes)
				)
			)
			(property "Datasheet" "https://mouser.com/datasheet/2/916/PUSB3F96-1600324.pdf"
				(at 25.4 -12.7 0)
				(effects
					(font
						(size 1.27 1.27)
						(thickness 0.15)
					)
					(justify left bottom)
					(hide yes)
				)
			)
			(property "Description" "TVS diode array, 10 kV, DFN-2510, 5.5 V, 0.5 pF"
				(at 0 0 0)
				(effects
					(font
						(size 1.27 1.27)
					)
					(hide yes)
				)
			)
			(property "Manufacturer" "Nexperia"
				(at 25.4 -15.24 0)
				(effects
					(font
						(size 1.27 1.27)
						(thickness 0.15)
					)
					(justify left bottom)
					(hide yes)
				)
			)
			(property "MPN" "PUSB3F96X"
				(at 25.4 -5.08 0)
				(effects
					(font
						(size 1.27 1.27)
						(thickness 0.15)
					)
					(justify left bottom)
				)
			)
			(property "Author" "Antmicro"
				(at 25.4 -17.78 0)
				(effects
					(font
						(size 1.27 1.27)
						(thickness 0.15)
					)
					(justify left bottom)
					(hide yes)
				)
			)
			(property "License" "Apache-2.0"
				(at 25.4 -20.32 0)
				(effects
					(font
						(size 1.27 1.27)
						(thickness 0.15)
					)
					(justify left bottom)
					(hide yes)
				)
			)
			(property "ki_keywords" "SMT, DIODE, SEMICONDUCTOR, TVS, ESD"
				(at 0 0 0)
				(effects
					(font
						(size 1.27 1.27)
					)
					(hide yes)
				)
			)
			(symbol "PUSB3F96X_PASS_1_1"
				(rectangle
					(start 2.54 -12.7)
					(end 12.7 2.54)
					(stroke
						(width 0.254)
						(type default)
					)
					(fill
						(type background)
					)
				)
				(polyline
					(pts
						(xy 8.382 -3.81) (xy 9.906 -3.81) (xy 9.906 -4.064)
					)
					(stroke
						(width 0.254)
						(type default)
					)
					(fill
						(type none)
					)
				)
				(polyline
					(pts
						(xy 9.144 -1.524) (xy 9.144 -7.112)
					)
					(stroke
						(width 0.254)
						(type default)
					)
					(fill
						(type none)
					)
				)
				(polyline
					(pts
						(xy 10.16 -5.334) (xy 9.144 -3.81) (xy 8.128 -5.334) (xy 10.16 -5.334)
					)
					(stroke
						(width 0.254)
						(type default)
					)
					(fill
						(type outline)
					)
				)
				(pin passive line
					(at 0 0 0)
					(length 2.54)
					(name "CH1"
						(effects
							(font
								(size 1.27 1.27)
							)
						)
					)
					(number "1"
						(effects
							(font
								(size 1.27 1.27)
							)
						)
					)
				)
				(pin passive line
					(at 0 0 0)
					(length 2.54)
					(hide yes)
					(name "CH1"
						(effects
							(font
								(size 1.27 1.27)
							)
						)
					)
					(number "10"
						(effects
							(font
								(size 1.27 1.27)
							)
						)
					)
				)
				(pin passive line
					(at 0 -2.54 0)
					(length 2.54)
					(name "CH2"
						(effects
							(font
								(size 1.27 1.27)
							)
						)
					)
					(number "2"
						(effects
							(font
								(size 1.27 1.27)
							)
						)
					)
				)
				(pin passive line
					(at 0 -2.54 0)
					(length 2.54)
					(hide yes)
					(name "CH2"
						(effects
							(font
								(size 1.27 1.27)
							)
						)
					)
					(number "9"
						(effects
							(font
								(size 1.27 1.27)
							)
						)
					)
				)
				(pin passive line
					(at 0 -5.08 0)
					(length 2.54)
					(name "CH3"
						(effects
							(font
								(size 1.27 1.27)
							)
						)
					)
					(number "4"
						(effects
							(font
								(size 1.27 1.27)
							)
						)
					)
				)
				(pin passive line
					(at 0 -5.08 0)
					(length 2.54)
					(hide yes)
					(name "CH3"
						(effects
							(font
								(size 1.27 1.27)
							)
						)
					)
					(number "7"
						(effects
							(font
								(size 1.27 1.27)
							)
						)
					)
				)
				(pin passive line
					(at 0 -7.62 0)
					(length 2.54)
					(name "CH4"
						(effects
							(font
								(size 1.27 1.27)
							)
						)
					)
					(number "5"
						(effects
							(font
								(size 1.27 1.27)
							)
						)
					)
				)
				(pin passive line
					(at 0 -7.62 0)
					(length 2.54)
					(hide yes)
					(name "CH4"
						(effects
							(font
								(size 1.27 1.27)
							)
						)
					)
					(number "6"
						(effects
							(font
								(size 1.27 1.27)
							)
						)
					)
				)
				(pin passive line
					(at 0 -10.16 0)
					(length 2.54)
					(name "GND"
						(effects
							(font
								(size 1.27 1.27)
							)
						)
					)
					(number "3"
						(effects
							(font
								(size 1.27 1.27)
							)
						)
					)
				)
				(pin passive line
					(at 0 -10.16 0)
					(length 2.54)
					(hide yes)
					(name "GND"
						(effects
							(font
								(size 1.27 1.27)
							)
						)
					)
					(number "8"
						(effects
							(font
								(size 1.27 1.27)
							)
						)
					)
				)
			)
		)
	(symbol "antmicroTVSDiodes:SMF4L15A"
			(pin_numbers
				(hide yes)
			)
			(pin_names
				(hide yes)
			)
			(exclude_from_sim no)
			(in_bom yes)
			(on_board yes)
			(property "Reference" "D"
				(at 26.67 -5.08 0)
				(effects
					(font
						(size 1.27 1.27)
						(thickness 0.15)
					)
					(justify left bottom)
				)
			)
			(property "Value" "SMF4L15A"
				(at 26.67 -15.24 0)
				(effects
					(font
						(size 1.27 1.27)
						(thickness 0.15)
					)
					(justify left bottom)
					(hide yes)
				)
			)
			(property "Footprint" "antmicro-footprints:SOD-123FL"
				(at 26.67 -10.16 0)
				(effects
					(font
						(size 1.27 1.27)
						(thickness 0.15)
					)
					(justify left bottom)
					(hide yes)
				)
			)
			(property "Datasheet" "https://www.littelfuse.com/media?resourcetype=datasheets&itemid=d2ba8fab-1de3-4176-8530-f36ecb0b8799&filename=smf4l"
				(at 26.67 -12.7 0)
				(effects
					(font
						(size 1.27 1.27)
						(thickness 0.15)
					)
					(justify left bottom)
					(hide yes)
				)
			)
			(property "Description" "Unidirectional TVS, 30 kV,  SOD-123FL, 15 V, 600 pF"
				(at 0 0 0)
				(effects
					(font
						(size 1.27 1.27)
					)
					(hide yes)
				)
			)
			(property "MPN" "SMF4L15A"
				(at 26.67 -7.62 0)
				(effects
					(font
						(size 1.27 1.27)
						(thickness 0.15)
					)
					(justify left bottom)
				)
			)
			(property "Manufacturer" "Littelfuse"
				(at 26.67 -17.78 0)
				(effects
					(font
						(size 1.27 1.27)
						(thickness 0.15)
					)
					(justify left bottom)
					(hide yes)
				)
			)
			(property "Author" "Antmicro"
				(at 26.67 -20.32 0)
				(effects
					(font
						(size 1.27 1.27)
						(thickness 0.15)
					)
					(justify left bottom)
					(hide yes)
				)
			)
			(property "License" "Apache-2.0"
				(at 26.67 -22.86 0)
				(effects
					(font
						(size 1.27 1.27)
						(thickness 0.15)
					)
					(justify left bottom)
					(hide yes)
				)
			)
			(property "ki_keywords" "DIODE, SEMICONDUCTOR, TVS, ESD"
				(at 0 0 0)
				(effects
					(font
						(size 1.27 1.27)
					)
					(hide yes)
				)
			)
			(symbol "SMF4L15A_0_1"
				(polyline
					(pts
						(xy 1.905 0) (xy 0.635 0)
					)
					(stroke
						(width 0)
						(type default)
					)
					(fill
						(type none)
					)
				)
				(polyline
					(pts
						(xy 4.445 0) (xy 3.175 0)
					)
					(stroke
						(width 0)
						(type default)
					)
					(fill
						(type none)
					)
				)
			)
			(symbol "SMF4L15A_1_1"
				(polyline
					(pts
						(xy 1.778 1.016) (xy 1.397 1.016)
					)
					(stroke
						(width 0.254)
						(type default)
					)
					(fill
						(type none)
					)
				)
				(polyline
					(pts
						(xy 1.778 1.016) (xy 1.778 -1.016)
					)
					(stroke
						(width 0.254)
						(type default)
					)
					(fill
						(type none)
					)
				)
				(polyline
					(pts
						(xy 2.159 -1.016) (xy 1.778 -1.016)
					)
					(stroke
						(width 0.254)
						(type default)
					)
					(fill
						(type none)
					)
				)
				(polyline
					(pts
						(xy 3.302 1.016) (xy 3.302 -1.016) (xy 1.778 0) (xy 3.302 1.016)
					)
					(stroke
						(width 0.254)
						(type default)
					)
					(fill
						(type outline)
					)
				)
				(pin passive line
					(at 0 0 0)
					(length 0.635)
					(name "C"
						(effects
							(font
								(size 1.27 1.27)
							)
						)
					)
					(number "1"
						(effects
							(font
								(size 1.27 1.27)
							)
						)
					)
				)
				(pin passive line
					(at 5.08 0 180)
					(length 0.635)
					(name "A"
						(effects
							(font
								(size 1.27 1.27)
							)
						)
					)
					(number "2"
						(effects
							(font
								(size 1.27 1.27)
							)
						)
					)
				)
			)
		)
	(symbol "antmicroTVSDiodes:TPD1E0B04_XDFN-2"
			(pin_numbers
				(hide yes)
			)
			(pin_names
				(hide yes)
			)
			(exclude_from_sim no)
			(in_bom yes)
			(on_board yes)
			(property "Reference" "D"
				(at 15.24 0 0)
				(effects
					(font
						(size 1.27 1.27)
						(thickness 0.15)
					)
					(justify left bottom)
				)
			)
			(property "Value" "TPD1E0B04_XDFN-2"
				(at 15.24 -10.16 0)
				(effects
					(font
						(size 1.27 1.27)
						(thickness 0.15)
					)
					(justify left bottom)
					(hide yes)
				)
			)
			(property "Footprint" "antmicro-footprints:XDFN-2_1x0.60mm"
				(at 15.24 -5.08 0)
				(effects
					(font
						(size 1.27 1.27)
						(thickness 0.15)
					)
					(justify left bottom)
					(hide yes)
				)
			)
			(property "Datasheet" "https://www.ti.com/general/docs/suppproductinfo.tsp?distId=26&gotoUrl=https://www.ti.com/lit/gpn/tpd1e0b04"
				(at 15.24 -7.62 0)
				(effects
					(font
						(size 1.27 1.27)
						(thickness 0.15)
					)
					(justify left bottom)
					(hide yes)
				)
			)
			(property "Description" "Bidirectional TVS, 8 kV,  XDFN-2, 3.6 V, 0.18 pF"
				(at 0 0 0)
				(effects
					(font
						(size 1.27 1.27)
					)
					(hide yes)
				)
			)
			(property "MPN" "TPD1E0B04DPYR"
				(at 15.24 -2.54 0)
				(effects
					(font
						(size 1.27 1.27)
						(thickness 0.15)
					)
					(justify left bottom)
				)
			)
			(property "Manufacturer" "Texas Instruments"
				(at 15.24 -12.7 0)
				(effects
					(font
						(size 1.27 1.27)
						(thickness 0.15)
					)
					(justify left bottom)
					(hide yes)
				)
			)
			(property "Author" "Antmicro"
				(at 15.24 -15.24 0)
				(effects
					(font
						(size 1.27 1.27)
						(thickness 0.15)
					)
					(justify left bottom)
					(hide yes)
				)
			)
			(property "License" "Apache-2.0"
				(at 15.24 -17.78 0)
				(effects
					(font
						(size 1.27 1.27)
						(thickness 0.15)
					)
					(justify left bottom)
					(hide yes)
				)
			)
			(property "ki_keywords" "DIODE, SEMICONDUCTOR, TVS, ESD"
				(at 0 0 0)
				(effects
					(font
						(size 1.27 1.27)
					)
					(hide yes)
				)
			)
			(symbol "TPD1E0B04_XDFN-2_0_0"
				(text ""
					(at 7.62 -1.27 0)
					(effects
						(font
							(size 1.27 1.27)
						)
					)
				)
			)
			(symbol "TPD1E0B04_XDFN-2_0_1"
				(polyline
					(pts
						(xy 0.635 0) (xy 4.445 0)
					)
					(stroke
						(width 0)
						(type default)
					)
					(fill
						(type none)
					)
				)
			)
			(symbol "TPD1E0B04_XDFN-2_1_1"
				(polyline
					(pts
						(xy 1.016 -1.016) (xy 1.016 1.016) (xy 2.54 0) (xy 1.016 -1.016)
					)
					(stroke
						(width 0.254)
						(type default)
					)
					(fill
						(type outline)
					)
				)
				(polyline
					(pts
						(xy 2.54 1.016) (xy 2.159 1.016)
					)
					(stroke
						(width 0.254)
						(type default)
					)
					(fill
						(type none)
					)
				)
				(polyline
					(pts
						(xy 2.54 1.016) (xy 2.54 -1.016)
					)
					(stroke
						(width 0.254)
						(type default)
					)
					(fill
						(type none)
					)
				)
				(polyline
					(pts
						(xy 2.921 -1.016) (xy 2.54 -1.016)
					)
					(stroke
						(width 0.254)
						(type default)
					)
					(fill
						(type none)
					)
				)
				(polyline
					(pts
						(xy 4.064 1.016) (xy 4.064 -1.016) (xy 2.54 0) (xy 4.064 1.016)
					)
					(stroke
						(width 0.254)
						(type default)
					)
					(fill
						(type outline)
					)
				)
				(pin passive line
					(at 0 0 0)
					(length 0.635)
					(name "C"
						(effects
							(font
								(size 1.27 1.27)
							)
						)
					)
					(number "1"
						(effects
							(font
								(size 1.27 1.27)
							)
						)
					)
				)
				(pin passive line
					(at 5.08 0 180)
					(length 0.635)
					(name "A"
						(effects
							(font
								(size 1.27 1.27)
							)
						)
					)
					(number "2"
						(effects
							(font
								(size 1.27 1.27)
							)
						)
					)
				)
			)
		)
	(symbol "antmicroTestPoints:TP_0.75mm_SMD"
			(pin_names
				(hide yes)
			)
			(exclude_from_sim no)
			(in_bom no)
			(on_board yes)
			(property "Reference" "TP"
				(at 10.16 -1.27 0)
				(effects
					(font
						(size 1.27 1.27)
						(thickness 0.15)
					)
					(justify left bottom)
				)
			)
			(property "Value" "TP_0.75mm_SMD"
				(at 10.16 -3.81 0)
				(effects
					(font
						(size 1.27 1.27)
						(thickness 0.15)
					)
					(justify left bottom)
					(hide yes)
				)
			)
			(property "Footprint" "antmicro-footprints:TP_SMD_0.75mm"
				(at 10.16 -6.35 0)
				(effects
					(font
						(size 1.27 1.27)
						(thickness 0.15)
					)
					(justify left bottom)
					(hide yes)
				)
			)
			(property "Datasheet" ""
				(at 17.78 -12.7 0)
				(effects
					(font
						(size 1.27 1.27)
						(thickness 0.15)
					)
					(justify left bottom)
					(hide yes)
				)
			)
			(property "Description" "SMT test point"
				(at 0 0 0)
				(effects
					(font
						(size 1.27 1.27)
					)
					(hide yes)
				)
			)
			(property "MPN" ""
				(at 10.795 -11.43 0)
				(effects
					(font
						(size 1.27 1.27)
						(thickness 0.15)
					)
					(justify left bottom)
					(hide yes)
				)
			)
			(property "Manufacturer" ""
				(at 10.795 -6.35 0)
				(effects
					(font
						(size 1.27 1.27)
						(thickness 0.15)
					)
					(justify left bottom)
					(hide yes)
				)
			)
			(property "Author" "Antmicro"
				(at 10.16 -8.89 0)
				(effects
					(font
						(size 1.27 1.27)
						(thickness 0.15)
					)
					(justify left bottom)
					(hide yes)
				)
			)
			(property "License" "Apache-2.0"
				(at 10.16 -11.43 0)
				(effects
					(font
						(size 1.27 1.27)
						(thickness 0.15)
					)
					(justify left bottom)
					(hide yes)
				)
			)
			(property "ki_keywords" "TESTPOINT"
				(at 0 0 0)
				(effects
					(font
						(size 1.27 1.27)
					)
					(hide yes)
				)
			)
			(symbol "TP_0.75mm_SMD_1_1"
				(circle
					(center 3.175 0)
					(radius 0.635)
					(stroke
						(width 0.254)
						(type default)
					)
					(fill
						(type none)
					)
				)
				(pin passive line
					(at 0 0 0)
					(length 2.54)
					(name "1"
						(effects
							(font
								(size 1.27 1.27)
							)
						)
					)
					(number "1"
						(effects
							(font
								(size 1.27 1.27)
							)
						)
					)
				)
			)
		)
	(symbol "antmicroTransistorsFETsMOSFETsSingle:PJE138K"
			(pin_names
				(offset 0)
			)
			(exclude_from_sim no)
			(in_bom no)
			(on_board yes)
			(property "Reference" "Q"
				(at 22.86 -6.35 0)
				(effects
					(font
						(size 1.27 1.27)
						(thickness 0.15)
					)
					(justify left bottom)
				)
			)
			(property "Value" "PJE138K"
				(at 22.86 -8.89 0)
				(effects
					(font
						(size 1.27 1.27)
						(thickness 0.15)
					)
					(justify left bottom)
					(hide yes)
				)
			)
			(property "Footprint" "antmicro-footprints:SOT-523"
				(at 22.86 -11.43 0)
				(effects
					(font
						(size 1.27 1.27)
						(thickness 0.15)
					)
					(justify left bottom)
					(hide yes)
				)
			)
			(property "Datasheet" "https://www.mouser.com/datasheet/2/1057/PJE138K-1876698.pdf"
				(at 22.86 -13.97 0)
				(effects
					(font
						(size 1.27 1.27)
						(thickness 0.15)
					)
					(justify left bottom)
					(hide yes)
				)
			)
			(property "Description" "MOSFET, N Channel, 50V, 0.35A, 4.5 ohm, SOT-523, Surface Mount"
				(at 22.86 -26.67 0)
				(effects
					(font
						(size 1.27 1.27)
					)
					(justify left bottom)
					(hide yes)
				)
			)
			(property "MPN" "PJE138K_R1_00001"
				(at 22.86 -16.51 0)
				(effects
					(font
						(size 1.27 1.27)
						(thickness 0.15)
					)
					(justify left bottom)
				)
			)
			(property "Manufacturer" "PANJIT"
				(at 22.86 -19.05 0)
				(effects
					(font
						(size 1.27 1.27)
						(thickness 0.15)
					)
					(justify left bottom)
					(hide yes)
				)
			)
			(property "Author" "Antmicro"
				(at 22.86 -21.59 0)
				(effects
					(font
						(size 1.27 1.27)
						(thickness 0.15)
					)
					(justify left bottom)
					(hide yes)
				)
			)
			(property "License" "Apache-2.0"
				(at 22.86 -24.13 0)
				(effects
					(font
						(size 1.27 1.27)
						(thickness 0.15)
					)
					(justify left bottom)
					(hide yes)
				)
			)
			(property "ki_keywords" "SMT, TRANSISTOR, SEMICONDUCTOR, MOSFET, NMOS"
				(at 0 0 0)
				(effects
					(font
						(size 1.27 1.27)
					)
					(hide yes)
				)
			)
			(symbol "PJE138K_1_1"
				(polyline
					(pts
						(xy 1.27 0) (xy 3.302 0) (xy 3.302 3.937)
					)
					(stroke
						(width 0.254)
						(type default)
					)
					(fill
						(type none)
					)
				)
				(polyline
					(pts
						(xy 3.81 4.445) (xy 3.81 3.429)
					)
					(stroke
						(width 0.254)
						(type default)
					)
					(fill
						(type background)
					)
				)
				(polyline
					(pts
						(xy 3.81 2.54) (xy 3.81 3.048)
					)
					(stroke
						(width 0.254)
						(type default)
					)
					(fill
						(type background)
					)
				)
				(polyline
					(pts
						(xy 3.81 2.54) (xy 3.81 2.032)
					)
					(stroke
						(width 0.254)
						(type default)
					)
					(fill
						(type background)
					)
				)
				(polyline
					(pts
						(xy 3.81 2.54) (xy 4.572 3.048) (xy 4.572 2.032) (xy 3.81 2.54)
					)
					(stroke
						(width 0.254)
						(type default)
					)
					(fill
						(type outline)
					)
				)
				(polyline
					(pts
						(xy 3.81 1.143) (xy 3.81 1.651)
					)
					(stroke
						(width 0.254)
						(type default)
					)
					(fill
						(type background)
					)
				)
				(polyline
					(pts
						(xy 3.81 1.143) (xy 3.81 0.635)
					)
					(stroke
						(width 0.254)
						(type default)
					)
					(fill
						(type background)
					)
				)
				(circle
					(center 5.08 2.54)
					(radius 3.302)
					(stroke
						(width 0.254)
						(type default)
					)
					(fill
						(type background)
					)
				)
				(polyline
					(pts
						(xy 6.223 0.635) (xy 7.366 0.635) (xy 7.366 3.937) (xy 7.366 4.445) (xy 6.223 4.445)
					)
					(stroke
						(width 0.254)
						(type default)
					)
					(fill
						(type none)
					)
				)
				(polyline
					(pts
						(xy 6.35 6.35) (xy 6.35 3.937) (xy 3.81 3.937)
					)
					(stroke
						(width 0.254)
						(type default)
					)
					(fill
						(type none)
					)
				)
				(circle
					(center 6.35 4.445)
					(radius 0.127)
					(stroke
						(width 0.254)
						(type default)
					)
					(fill
						(type background)
					)
				)
				(polyline
					(pts
						(xy 6.35 1.143) (xy 3.81 1.143)
					)
					(stroke
						(width 0.254)
						(type default)
					)
					(fill
						(type background)
					)
				)
				(circle
					(center 6.35 1.143)
					(radius 0.127)
					(stroke
						(width 0.254)
						(type default)
					)
					(fill
						(type background)
					)
				)
				(circle
					(center 6.35 0.635)
					(radius 0.127)
					(stroke
						(width 0.254)
						(type default)
					)
					(fill
						(type background)
					)
				)
				(polyline
					(pts
						(xy 6.35 -1.27) (xy 6.35 2.54) (xy 3.81 2.54)
					)
					(stroke
						(width 0.254)
						(type default)
					)
					(fill
						(type none)
					)
				)
				(polyline
					(pts
						(xy 7.366 3.048) (xy 6.858 2.286) (xy 7.874 2.286) (xy 7.366 3.048)
					)
					(stroke
						(width 0.254)
						(type default)
					)
					(fill
						(type outline)
					)
				)
				(polyline
					(pts
						(xy 7.874 3.048) (xy 6.858 3.048)
					)
					(stroke
						(width 0.254)
						(type default)
					)
					(fill
						(type background)
					)
				)
				(pin input line
					(at 0 0 0)
					(length 2.54)
					(name "G"
						(effects
							(font
								(size 1.27 1.27)
							)
						)
					)
					(number "1"
						(effects
							(font
								(size 1.27 1.27)
							)
						)
					)
				)
				(pin passive line
					(at 6.35 7.62 270)
					(length 2.54)
					(name "D"
						(effects
							(font
								(size 1.27 1.27)
							)
						)
					)
					(number "3"
						(effects
							(font
								(size 1.27 1.27)
							)
						)
					)
				)
				(pin passive line
					(at 6.35 -2.54 90)
					(length 2.54)
					(name "S"
						(effects
							(font
								(size 1.27 1.27)
							)
						)
					)
					(number "2"
						(effects
							(font
								(size 1.27 1.27)
							)
						)
					)
				)
			)
		)
	(symbol "antmicroTransistorsFETsMOSFETsSingle:SQS401EN-T1_BE3"
			(pin_names
				(offset 0)
			)
			(exclude_from_sim no)
			(in_bom no)
			(on_board yes)
			(property "Reference" "Q"
				(at 15.24 -5.08 0)
				(effects
					(font
						(size 1.27 1.27)
						(thickness 0.15)
					)
					(justify left bottom)
				)
			)
			(property "Value" "SQS401EN-T1_BE3"
				(at 15.24 -10.16 0)
				(effects
					(font
						(size 1.27 1.27)
						(thickness 0.15)
					)
					(justify left bottom)
					(hide yes)
				)
			)
			(property "Footprint" "antmicro-footprints:Vishay_PowerPAK_1212-8_Single"
				(at 15.24 -12.7 0)
				(effects
					(font
						(size 1.27 1.27)
						(thickness 0.15)
					)
					(justify left bottom)
					(hide yes)
				)
			)
			(property "Datasheet" "https://www.vishay.com/docs/65529/sqs401en.pdf"
				(at 15.24 -15.24 0)
				(effects
					(font
						(size 1.27 1.27)
						(thickness 0.15)
					)
					(justify left bottom)
					(hide yes)
				)
			)
			(property "Description" "MOSFET, P Channel, 40 V, 16A, 0.047 ohm, PowerPAK 1212-8, Surface Mount"
				(at 53.34 -24.384 0)
				(effects
					(font
						(size 1.27 1.27)
					)
					(hide yes)
				)
			)
			(property "MPN" "SQS401EN-T1_BE3"
				(at 15.24 -7.62 0)
				(effects
					(font
						(size 1.27 1.27)
						(thickness 0.15)
					)
					(justify left bottom)
				)
			)
			(property "Manufacturer" "Vishay"
				(at 15.24 -17.78 0)
				(effects
					(font
						(size 1.27 1.27)
						(thickness 0.15)
					)
					(justify left bottom)
					(hide yes)
				)
			)
			(property "Author" "Antmicro"
				(at 15.24 -20.32 0)
				(effects
					(font
						(size 1.27 1.27)
						(thickness 0.15)
					)
					(justify left bottom)
					(hide yes)
				)
			)
			(property "License" "Apache-2.0"
				(at 15.24 -22.86 0)
				(effects
					(font
						(size 1.27 1.27)
						(thickness 0.15)
					)
					(justify left bottom)
					(hide yes)
				)
			)
			(property "ki_keywords" "SMT, TRANSISTOR, SEMICONDUCTOR, MOSFET, PMOS"
				(at 0 0 0)
				(effects
					(font
						(size 1.27 1.27)
					)
					(hide yes)
				)
			)
			(symbol "SQS401EN-T1_BE3_1_1"
				(polyline
					(pts
						(xy 1.27 0) (xy 3.302 0) (xy 3.302 3.937)
					)
					(stroke
						(width 0.254)
						(type default)
					)
					(fill
						(type none)
					)
				)
				(polyline
					(pts
						(xy 3.81 4.445) (xy 3.81 3.429)
					)
					(stroke
						(width 0.254)
						(type default)
					)
					(fill
						(type background)
					)
				)
				(polyline
					(pts
						(xy 3.81 2.54) (xy 3.81 3.048)
					)
					(stroke
						(width 0.254)
						(type default)
					)
					(fill
						(type background)
					)
				)
				(polyline
					(pts
						(xy 3.81 2.54) (xy 3.81 2.032)
					)
					(stroke
						(width 0.254)
						(type default)
					)
					(fill
						(type background)
					)
				)
				(polyline
					(pts
						(xy 3.81 1.143) (xy 3.81 1.651)
					)
					(stroke
						(width 0.254)
						(type default)
					)
					(fill
						(type background)
					)
				)
				(polyline
					(pts
						(xy 3.81 1.143) (xy 3.81 0.635)
					)
					(stroke
						(width 0.254)
						(type default)
					)
					(fill
						(type background)
					)
				)
				(circle
					(center 5.08 2.54)
					(radius 3.302)
					(stroke
						(width 0.254)
						(type default)
					)
					(fill
						(type background)
					)
				)
				(polyline
					(pts
						(xy 6.096 2.54) (xy 5.334 2.032) (xy 5.334 3.048) (xy 6.096 2.54)
					)
					(stroke
						(width 0.254)
						(type default)
					)
					(fill
						(type outline)
					)
				)
				(polyline
					(pts
						(xy 6.223 0.635) (xy 7.366 0.635) (xy 7.366 3.937) (xy 7.366 4.445) (xy 6.223 4.445)
					)
					(stroke
						(width 0.254)
						(type default)
					)
					(fill
						(type none)
					)
				)
				(polyline
					(pts
						(xy 6.35 6.35) (xy 6.35 3.937) (xy 3.81 3.937)
					)
					(stroke
						(width 0.254)
						(type default)
					)
					(fill
						(type none)
					)
				)
				(circle
					(center 6.35 4.445)
					(radius 0.127)
					(stroke
						(width 0.254)
						(type default)
					)
					(fill
						(type background)
					)
				)
				(polyline
					(pts
						(xy 6.35 1.143) (xy 3.81 1.143)
					)
					(stroke
						(width 0.254)
						(type default)
					)
					(fill
						(type background)
					)
				)
				(circle
					(center 6.35 1.143)
					(radius 0.127)
					(stroke
						(width 0.254)
						(type default)
					)
					(fill
						(type background)
					)
				)
				(circle
					(center 6.35 0.635)
					(radius 0.127)
					(stroke
						(width 0.254)
						(type default)
					)
					(fill
						(type background)
					)
				)
				(polyline
					(pts
						(xy 6.35 -1.27) (xy 6.35 2.54) (xy 3.81 2.54)
					)
					(stroke
						(width 0.254)
						(type default)
					)
					(fill
						(type none)
					)
				)
				(polyline
					(pts
						(xy 7.366 2.286) (xy 7.874 3.048) (xy 6.858 3.048) (xy 7.366 2.286)
					)
					(stroke
						(width 0.254)
						(type default)
					)
					(fill
						(type outline)
					)
				)
				(polyline
					(pts
						(xy 7.874 2.286) (xy 6.858 2.286)
					)
					(stroke
						(width 0.254)
						(type default)
					)
					(fill
						(type background)
					)
				)
				(pin input line
					(at 0 0 0)
					(length 2.54)
					(name "G"
						(effects
							(font
								(size 1.27 1.27)
							)
						)
					)
					(number "4"
						(effects
							(font
								(size 1.27 1.27)
							)
						)
					)
				)
				(pin passive line
					(at 6.35 7.62 270)
					(length 2.54)
					(name "D"
						(effects
							(font
								(size 1.27 1.27)
							)
						)
					)
					(number "5"
						(effects
							(font
								(size 1.27 1.27)
							)
						)
					)
				)
				(pin passive line
					(at 6.35 -2.54 90)
					(length 2.54)
					(name "S"
						(effects
							(font
								(size 1.27 1.27)
							)
						)
					)
					(number "1"
						(effects
							(font
								(size 1.27 1.27)
							)
						)
					)
				)
				(pin passive line
					(at 6.35 -2.54 90)
					(length 2.54)
					(hide yes)
					(name "S"
						(effects
							(font
								(size 1.27 1.27)
							)
						)
					)
					(number "2"
						(effects
							(font
								(size 1.27 1.27)
							)
						)
					)
				)
				(pin passive line
					(at 6.35 -2.54 90)
					(length 2.54)
					(hide yes)
					(name "S"
						(effects
							(font
								(size 1.27 1.27)
							)
						)
					)
					(number "3"
						(effects
							(font
								(size 1.27 1.27)
							)
						)
					)
				)
			)
		)
	(symbol "antmicroTransistorsFETsMOSFETsSingle:SSM3J332R"
			(pin_names
				(offset 0)
			)
			(exclude_from_sim no)
			(in_bom no)
			(on_board yes)
			(property "Reference" "Q"
				(at 20.32 2.54 0)
				(effects
					(font
						(size 1.27 1.27)
						(thickness 0.15)
					)
					(justify left bottom)
				)
			)
			(property "Value" "SSM3J332R"
				(at 20.32 0 0)
				(effects
					(font
						(size 1.27 1.27)
						(thickness 0.15)
					)
					(justify left bottom)
					(hide yes)
				)
			)
			(property "Footprint" "antmicro-footprints:SOT-23-3"
				(at 20.32 -2.54 0)
				(effects
					(font
						(size 1.27 1.27)
						(thickness 0.15)
					)
					(justify left bottom)
					(hide yes)
				)
			)
			(property "Datasheet" "https://www.mouser.com/datasheet/2/408/SSM3J332R_datasheet_en_20181015-1150575.pdf"
				(at 20.32 -7.62 0)
				(effects
					(font
						(size 1.27 1.27)
						(thickness 0.15)
					)
					(justify left bottom)
					(hide yes)
				)
			)
			(property "Description" "Power MOSFET, P Channel, 30 V, 6 A, 0.036 ohm, SOT-23F, Surface Mount"
				(at 20.32 -5.08 0)
				(effects
					(font
						(size 1.27 1.27)
					)
					(justify left bottom)
					(hide yes)
				)
			)
			(property "MPN" "SSM3J332R,LF"
				(at 20.066 -10.16 0)
				(effects
					(font
						(size 1.27 1.27)
					)
					(justify left bottom)
				)
			)
			(property "Manufacturer" "Toshiba"
				(at 20.32 -17.78 0)
				(effects
					(font
						(size 1.27 1.27)
					)
					(justify left bottom)
					(hide yes)
				)
			)
			(property "Author" "Antmicro"
				(at 20.32 -12.7 0)
				(effects
					(font
						(size 1.27 1.27)
					)
					(justify left bottom)
					(hide yes)
				)
			)
			(property "License" "Apache-2.0"
				(at 20.32 -15.24 0)
				(effects
					(font
						(size 1.27 1.27)
					)
					(justify left bottom)
					(hide yes)
				)
			)
			(property "ki_keywords" "PMOS"
				(at 0 0 0)
				(effects
					(font
						(size 1.27 1.27)
					)
					(hide yes)
				)
			)
			(symbol "SSM3J332R_1_1"
				(polyline
					(pts
						(xy 1.27 0) (xy 3.302 0) (xy 3.302 3.937)
					)
					(stroke
						(width 0.254)
						(type default)
					)
					(fill
						(type none)
					)
				)
				(polyline
					(pts
						(xy 3.81 4.445) (xy 3.81 3.429)
					)
					(stroke
						(width 0.254)
						(type default)
					)
					(fill
						(type background)
					)
				)
				(polyline
					(pts
						(xy 3.81 2.54) (xy 3.81 3.048)
					)
					(stroke
						(width 0.254)
						(type default)
					)
					(fill
						(type background)
					)
				)
				(polyline
					(pts
						(xy 3.81 2.54) (xy 3.81 2.032)
					)
					(stroke
						(width 0.254)
						(type default)
					)
					(fill
						(type background)
					)
				)
				(polyline
					(pts
						(xy 3.81 1.143) (xy 3.81 1.651)
					)
					(stroke
						(width 0.254)
						(type default)
					)
					(fill
						(type background)
					)
				)
				(polyline
					(pts
						(xy 3.81 1.143) (xy 3.81 0.635)
					)
					(stroke
						(width 0.254)
						(type default)
					)
					(fill
						(type background)
					)
				)
				(circle
					(center 5.08 2.54)
					(radius 3.302)
					(stroke
						(width 0.254)
						(type default)
					)
					(fill
						(type background)
					)
				)
				(polyline
					(pts
						(xy 6.096 2.54) (xy 5.334 2.032) (xy 5.334 3.048) (xy 6.096 2.54)
					)
					(stroke
						(width 0.254)
						(type default)
					)
					(fill
						(type outline)
					)
				)
				(polyline
					(pts
						(xy 6.223 0.635) (xy 7.366 0.635) (xy 7.366 3.937) (xy 7.366 4.445) (xy 6.223 4.445)
					)
					(stroke
						(width 0.254)
						(type default)
					)
					(fill
						(type none)
					)
				)
				(polyline
					(pts
						(xy 6.35 6.35) (xy 6.35 3.937) (xy 3.81 3.937)
					)
					(stroke
						(width 0.254)
						(type default)
					)
					(fill
						(type none)
					)
				)
				(circle
					(center 6.35 4.445)
					(radius 0.127)
					(stroke
						(width 0.254)
						(type default)
					)
					(fill
						(type background)
					)
				)
				(polyline
					(pts
						(xy 6.35 1.143) (xy 3.81 1.143)
					)
					(stroke
						(width 0.254)
						(type default)
					)
					(fill
						(type background)
					)
				)
				(circle
					(center 6.35 1.143)
					(radius 0.127)
					(stroke
						(width 0.254)
						(type default)
					)
					(fill
						(type background)
					)
				)
				(circle
					(center 6.35 0.635)
					(radius 0.127)
					(stroke
						(width 0.254)
						(type default)
					)
					(fill
						(type background)
					)
				)
				(polyline
					(pts
						(xy 6.35 -1.27) (xy 6.35 2.54) (xy 3.81 2.54)
					)
					(stroke
						(width 0.254)
						(type default)
					)
					(fill
						(type none)
					)
				)
				(polyline
					(pts
						(xy 7.366 2.286) (xy 7.874 3.048) (xy 6.858 3.048) (xy 7.366 2.286)
					)
					(stroke
						(width 0.254)
						(type default)
					)
					(fill
						(type outline)
					)
				)
				(polyline
					(pts
						(xy 7.874 2.286) (xy 6.858 2.286)
					)
					(stroke
						(width 0.254)
						(type default)
					)
					(fill
						(type background)
					)
				)
				(pin input line
					(at 0 0 0)
					(length 2.54)
					(name "G"
						(effects
							(font
								(size 1.27 1.27)
							)
						)
					)
					(number "1"
						(effects
							(font
								(size 1.27 1.27)
							)
						)
					)
				)
				(pin passive line
					(at 6.35 7.62 270)
					(length 2.54)
					(name "D"
						(effects
							(font
								(size 1.27 1.27)
							)
						)
					)
					(number "3"
						(effects
							(font
								(size 1.27 1.27)
							)
						)
					)
				)
				(pin passive line
					(at 6.35 -2.54 90)
					(length 2.54)
					(name "S"
						(effects
							(font
								(size 1.27 1.27)
							)
						)
					)
					(number "2"
						(effects
							(font
								(size 1.27 1.27)
							)
						)
					)
				)
			)
		)
	(symbol "antmicroUSBConnectors:USB-C_GCT_USB4105-GF-A"
			(exclude_from_sim no)
			(in_bom yes)
			(on_board yes)
			(property "Reference" "J"
				(at 38.1 -2.54 0)
				(effects
					(font
						(size 1.27 1.27)
						(thickness 0.15)
					)
					(justify left bottom)
				)
			)
			(property "Value" "USB-C_GCT_USB4105-GF-A"
				(at 38.1 -5.08 0)
				(effects
					(font
						(size 1.27 1.27)
						(thickness 0.15)
					)
					(justify left bottom)
					(hide yes)
				)
			)
			(property "Footprint" "antmicro-footprints:USB-C_Receptacle_GCT_USB4105-GF-A"
				(at 38.1 -7.62 0)
				(effects
					(font
						(size 1.27 1.27)
						(thickness 0.15)
					)
					(justify left bottom)
					(hide yes)
				)
			)
			(property "Datasheet" "https://gct.co/files/drawings/usb4105.pdf"
				(at 38.1 -10.16 0)
				(effects
					(font
						(size 1.27 1.27)
						(thickness 0.15)
					)
					(justify left bottom)
					(hide yes)
				)
			)
			(property "Description" "USB-C (USB TYPE-C) USB 2.0 Receptacle Connector 24 (16+8 Dummy) Position Surface Mount, Right Angle"
				(at 38.1 -22.86 0)
				(effects
					(font
						(size 1.27 1.27)
					)
					(justify left bottom)
					(hide yes)
				)
			)
			(property "Manufacturer" "GCT"
				(at 38.1 -12.7 0)
				(effects
					(font
						(size 1.27 1.27)
						(thickness 0.15)
					)
					(justify left bottom)
					(hide yes)
				)
			)
			(property "MPN" "USB4105-GF-A"
				(at 38.1 -15.24 0)
				(effects
					(font
						(size 1.27 1.27)
						(thickness 0.15)
					)
					(justify left bottom)
				)
			)
			(property "Author" "Antmicro"
				(at 38.1 -17.78 0)
				(effects
					(font
						(size 1.27 1.27)
						(thickness 0.15)
					)
					(justify left bottom)
					(hide yes)
				)
			)
			(property "License" "Apache-2.0"
				(at 38.1 -20.32 0)
				(effects
					(font
						(size 1.27 1.27)
						(thickness 0.15)
					)
					(justify left bottom)
					(hide yes)
				)
			)
			(property "ki_keywords" "USB, CONNECTOR, SMT, HORIZONTAL"
				(at 0 0 0)
				(effects
					(font
						(size 1.27 1.27)
					)
					(hide yes)
				)
			)
			(symbol "USB-C_GCT_USB4105-GF-A_1_1"
				(rectangle
					(start -22.86 2.54)
					(end -3.81 -38.1)
					(stroke
						(width 0.254)
						(type default)
					)
					(fill
						(type background)
					)
				)
				(circle
					(center -20.066 -18.034)
					(radius 0.284)
					(stroke
						(width 0.254)
						(type default)
					)
					(fill
						(type outline)
					)
				)
				(polyline
					(pts
						(xy -19.812 -16.383) (xy -19.177 -15.24) (xy -18.542 -16.383) (xy -19.812 -16.383)
					)
					(stroke
						(width 0.254)
						(type default)
					)
					(fill
						(type outline)
					)
				)
				(polyline
					(pts
						(xy -19.177 -19.558) (xy -18.288 -18.669) (xy -18.288 -18.034)
					)
					(stroke
						(width 0.254)
						(type default)
					)
					(fill
						(type background)
					)
				)
				(polyline
					(pts
						(xy -19.177 -19.939) (xy -20.066 -19.05) (xy -20.066 -18.415)
					)
					(stroke
						(width 0.254)
						(type default)
					)
					(fill
						(type background)
					)
				)
				(polyline
					(pts
						(xy -19.177 -20.701) (xy -19.177 -16.383)
					)
					(stroke
						(width 0.254)
						(type default)
					)
					(fill
						(type background)
					)
				)
				(circle
					(center -19.177 -20.828)
					(radius 0.5236)
					(stroke
						(width 0.254)
						(type default)
					)
					(fill
						(type outline)
					)
				)
				(rectangle
					(start -18.669 -18.034)
					(end -17.907 -17.272)
					(stroke
						(width 0.254)
						(type default)
					)
					(fill
						(type outline)
					)
				)
				(polyline
					(pts
						(xy -16.51 -21.59) (xy -16.51 -13.97)
					)
					(stroke
						(width 0.254)
						(type default)
					)
					(fill
						(type background)
					)
				)
				(rectangle
					(start -15.24 -21.59)
					(end -13.97 -13.97)
					(stroke
						(width 0.254)
						(type default)
					)
					(fill
						(type outline)
					)
				)
				(arc
					(start -15.24 -13.97)
					(mid -14.605 -13.3377)
					(end -13.97 -13.97)
					(stroke
						(width 0.254)
						(type default)
					)
					(fill
						(type outline)
					)
				)
				(arc
					(start -15.24 -13.97)
					(mid -14.605 -13.3377)
					(end -13.97 -13.97)
					(stroke
						(width 0.254)
						(type default)
					)
					(fill
						(type background)
					)
				)
				(arc
					(start -16.51 -13.97)
					(mid -14.605 -12.0733)
					(end -12.7 -13.97)
					(stroke
						(width 0.254)
						(type default)
					)
					(fill
						(type background)
					)
				)
				(arc
					(start -12.7 -21.59)
					(mid -14.605 -23.4867)
					(end -16.51 -21.59)
					(stroke
						(width 0.254)
						(type default)
					)
					(fill
						(type background)
					)
				)
				(arc
					(start -13.97 -21.59)
					(mid -14.605 -22.2223)
					(end -15.24 -21.59)
					(stroke
						(width 0.254)
						(type default)
					)
					(fill
						(type outline)
					)
				)
				(arc
					(start -13.97 -21.59)
					(mid -14.605 -22.2223)
					(end -15.24 -21.59)
					(stroke
						(width 0.254)
						(type default)
					)
					(fill
						(type background)
					)
				)
				(polyline
					(pts
						(xy -12.7 -13.97) (xy -12.7 -21.59)
					)
					(stroke
						(width 0.254)
						(type default)
					)
					(fill
						(type background)
					)
				)
				(pin power_in line
					(at 0 0 180)
					(length 3.81)
					(name "VBUS"
						(effects
							(font
								(size 1.27 1.27)
							)
						)
					)
					(number "A4"
						(effects
							(font
								(size 1.27 1.27)
							)
						)
					)
				)
				(pin passive line
					(at 0 0 180)
					(length 3.81)
					(hide yes)
					(name "VBUS"
						(effects
							(font
								(size 1.27 1.27)
							)
						)
					)
					(number "A9"
						(effects
							(font
								(size 1.27 1.27)
							)
						)
					)
				)
				(pin passive line
					(at 0 0 180)
					(length 3.81)
					(hide yes)
					(name "VBUS"
						(effects
							(font
								(size 1.27 1.27)
							)
						)
					)
					(number "B4"
						(effects
							(font
								(size 1.27 1.27)
							)
						)
					)
				)
				(pin passive line
					(at 0 0 180)
					(length 3.81)
					(hide yes)
					(name "VBUS"
						(effects
							(font
								(size 1.27 1.27)
							)
						)
					)
					(number "B9"
						(effects
							(font
								(size 1.27 1.27)
							)
						)
					)
				)
				(pin bidirectional line
					(at 0 -5.08 180)
					(length 3.81)
					(name "CC_{1}"
						(effects
							(font
								(size 1.27 1.27)
							)
						)
					)
					(number "A5"
						(effects
							(font
								(size 1.27 1.27)
							)
						)
					)
				)
				(pin bidirectional line
					(at 0 -7.62 180)
					(length 3.81)
					(name "CC_{2}"
						(effects
							(font
								(size 1.27 1.27)
							)
						)
					)
					(number "B5"
						(effects
							(font
								(size 1.27 1.27)
							)
						)
					)
				)
				(pin bidirectional line
					(at 0 -12.7 180)
					(length 3.81)
					(name "D_{A}+"
						(effects
							(font
								(size 1.27 1.27)
							)
						)
					)
					(number "A6"
						(effects
							(font
								(size 1.27 1.27)
							)
						)
					)
				)
				(pin bidirectional line
					(at 0 -15.24 180)
					(length 3.81)
					(name "D_{A}-"
						(effects
							(font
								(size 1.27 1.27)
							)
						)
					)
					(number "A7"
						(effects
							(font
								(size 1.27 1.27)
							)
						)
					)
				)
				(pin bidirectional line
					(at 0 -17.78 180)
					(length 3.81)
					(name "D_{B}+"
						(effects
							(font
								(size 1.27 1.27)
							)
						)
					)
					(number "B6"
						(effects
							(font
								(size 1.27 1.27)
							)
						)
					)
				)
				(pin bidirectional line
					(at 0 -20.32 180)
					(length 3.81)
					(name "D_{B}-"
						(effects
							(font
								(size 1.27 1.27)
							)
						)
					)
					(number "B7"
						(effects
							(font
								(size 1.27 1.27)
							)
						)
					)
				)
				(pin bidirectional line
					(at 0 -25.4 180)
					(length 3.81)
					(name "SBU_{1}"
						(effects
							(font
								(size 1.27 1.27)
							)
						)
					)
					(number "A8"
						(effects
							(font
								(size 1.27 1.27)
							)
						)
					)
				)
				(pin bidirectional line
					(at 0 -27.94 180)
					(length 3.81)
					(name "SBU_{2}"
						(effects
							(font
								(size 1.27 1.27)
							)
						)
					)
					(number "B8"
						(effects
							(font
								(size 1.27 1.27)
							)
						)
					)
				)
				(pin power_in line
					(at 0 -33.02 180)
					(length 3.81)
					(name "GND"
						(effects
							(font
								(size 1.27 1.27)
							)
						)
					)
					(number "A1"
						(effects
							(font
								(size 1.27 1.27)
							)
						)
					)
				)
				(pin passive line
					(at 0 -33.02 180)
					(length 3.81)
					(hide yes)
					(name "GND"
						(effects
							(font
								(size 1.27 1.27)
							)
						)
					)
					(number "A12"
						(effects
							(font
								(size 1.27 1.27)
							)
						)
					)
				)
				(pin passive line
					(at 0 -33.02 180)
					(length 3.81)
					(hide yes)
					(name "GND"
						(effects
							(font
								(size 1.27 1.27)
							)
						)
					)
					(number "B1"
						(effects
							(font
								(size 1.27 1.27)
							)
						)
					)
				)
				(pin passive line
					(at 0 -33.02 180)
					(length 3.81)
					(hide yes)
					(name "GND"
						(effects
							(font
								(size 1.27 1.27)
							)
						)
					)
					(number "B12"
						(effects
							(font
								(size 1.27 1.27)
							)
						)
					)
				)
				(pin passive line
					(at 0 -35.56 180)
					(length 3.81)
					(name "SH"
						(effects
							(font
								(size 1.27 1.27)
							)
						)
					)
					(number "SH"
						(effects
							(font
								(size 1.27 1.27)
							)
						)
					)
				)
			)
		)
	(symbol "antmicroVideoConnectors:HDMI-A_WE_685119134923"
			(exclude_from_sim no)
			(in_bom yes)
			(on_board yes)
			(property "Reference" "J"
				(at 35.56 -2.54 0)
				(effects
					(font
						(size 1.27 1.27)
						(thickness 0.15)
					)
					(justify left bottom)
				)
			)
			(property "Value" "HDMI-A_WE_685119134923"
				(at 35.56 -5.08 0)
				(effects
					(font
						(size 1.27 1.27)
						(thickness 0.15)
					)
					(justify left bottom)
					(hide yes)
				)
			)
			(property "Footprint" "antmicro-footprints:HDMI-A_Receptacle_WE_685119134923"
				(at 35.56 -7.62 0)
				(effects
					(font
						(size 1.27 1.27)
						(thickness 0.15)
					)
					(justify left bottom)
					(hide yes)
				)
			)
			(property "Datasheet" "https://www.we-online.com/components/products/datasheet/685119134923.pdf"
				(at 35.56 -10.16 0)
				(effects
					(font
						(size 1.27 1.27)
						(thickness 0.15)
					)
					(justify left bottom)
					(hide yes)
				)
			)
			(property "Description" "HDMI Receptacle Connector 19 Position Surface Mount, Right Angle; Through Hole"
				(at 0 0 0)
				(effects
					(font
						(size 1.27 1.27)
					)
					(hide yes)
				)
			)
			(property "MPN" "685119134923"
				(at 35.56 -12.7 0)
				(effects
					(font
						(size 1.27 1.27)
						(thickness 0.15)
					)
					(justify left bottom)
				)
			)
			(property "Manufacturer" "Würth Elektronik"
				(at 35.56 -15.24 0)
				(effects
					(font
						(size 1.27 1.27)
						(thickness 0.15)
					)
					(justify left bottom)
					(hide yes)
				)
			)
			(property "Author" "Antmicro"
				(at 35.56 -17.78 0)
				(effects
					(font
						(size 1.27 1.27)
						(thickness 0.15)
					)
					(justify left bottom)
					(hide yes)
				)
			)
			(property "License" "Apache-2.0"
				(at 35.56 -20.32 0)
				(effects
					(font
						(size 1.27 1.27)
						(thickness 0.15)
					)
					(justify left bottom)
					(hide yes)
				)
			)
			(property "ki_keywords" "HDMI, CONNECTOR, THT"
				(at 0 0 0)
				(effects
					(font
						(size 1.27 1.27)
					)
					(hide yes)
				)
			)
			(property "ki_fp_filters" "685119134923"
				(at 0 0 0)
				(effects
					(font
						(size 1.27 1.27)
					)
					(hide yes)
				)
			)
			(symbol "HDMI-A_WE_685119134923_0_0"
				(polyline
					(pts
						(xy 13.97 0) (xy 13.97 1.524) (xy 13.97 0.762) (xy 15.875 0.762) (xy 15.875 1.524) (xy 15.875 0)
					)
					(stroke
						(width 0.635)
						(type default)
					)
					(fill
						(type none)
					)
				)
				(polyline
					(pts
						(xy 16.637 1.524) (xy 18.288 1.524) (xy 18.542 1.27) (xy 18.542 0.254) (xy 18.288 0) (xy 16.637 0)
						(xy 16.637 0.762)
					)
					(stroke
						(width 0.635)
						(type default)
					)
					(fill
						(type none)
					)
				)
				(polyline
					(pts
						(xy 22.098 0) (xy 22.098 1.524)
					)
					(stroke
						(width 0.635)
						(type default)
					)
					(fill
						(type none)
					)
				)
			)
			(symbol "HDMI-A_WE_685119134923_0_1"
				(polyline
					(pts
						(xy 10.16 -15.24) (xy 13.97 -15.24) (xy 15.875 -17.145) (xy 15.875 -28.575) (xy 13.97 -30.48)
						(xy 10.16 -30.48) (xy 10.16 -15.24)
					)
					(stroke
						(width 0.635)
						(type default)
					)
					(fill
						(type none)
					)
				)
				(polyline
					(pts
						(xy 12.065 -16.51) (xy 13.335 -16.51) (xy 13.97 -17.145) (xy 13.97 -28.575) (xy 13.335 -29.21)
						(xy 12.065 -29.21) (xy 12.065 -16.51)
					)
					(stroke
						(width 0.254)
						(type default)
					)
					(fill
						(type outline)
					)
				)
				(polyline
					(pts
						(xy 19.304 0) (xy 19.304 1.524) (xy 20.32 1.524) (xy 20.32 0) (xy 20.32 1.524) (xy 21.082 1.524)
						(xy 21.336 1.27) (xy 21.336 0)
					)
					(stroke
						(width 0.635)
						(type default)
					)
					(fill
						(type none)
					)
				)
			)
			(symbol "HDMI-A_WE_685119134923_1_1"
				(rectangle
					(start 2.54 2.54)
					(end 22.86 -53.34)
					(stroke
						(width 0.254)
						(type default)
					)
					(fill
						(type background)
					)
				)
				(pin bidirectional line
					(at 0 0 0)
					(length 2.54)
					(name "D2+"
						(effects
							(font
								(size 1.27 1.27)
							)
						)
					)
					(number "1"
						(effects
							(font
								(size 1.27 1.27)
							)
						)
					)
				)
				(pin bidirectional line
					(at 0 -2.54 0)
					(length 2.54)
					(name "D2-"
						(effects
							(font
								(size 1.27 1.27)
							)
						)
					)
					(number "3"
						(effects
							(font
								(size 1.27 1.27)
							)
						)
					)
				)
				(pin bidirectional line
					(at 0 -7.62 0)
					(length 2.54)
					(name "D1+"
						(effects
							(font
								(size 1.27 1.27)
							)
						)
					)
					(number "4"
						(effects
							(font
								(size 1.27 1.27)
							)
						)
					)
				)
				(pin bidirectional line
					(at 0 -10.16 0)
					(length 2.54)
					(name "D1-"
						(effects
							(font
								(size 1.27 1.27)
							)
						)
					)
					(number "6"
						(effects
							(font
								(size 1.27 1.27)
							)
						)
					)
				)
				(pin bidirectional line
					(at 0 -15.24 0)
					(length 2.54)
					(name "D0+"
						(effects
							(font
								(size 1.27 1.27)
							)
						)
					)
					(number "7"
						(effects
							(font
								(size 1.27 1.27)
							)
						)
					)
				)
				(pin bidirectional line
					(at 0 -17.78 0)
					(length 2.54)
					(name "D0-"
						(effects
							(font
								(size 1.27 1.27)
							)
						)
					)
					(number "9"
						(effects
							(font
								(size 1.27 1.27)
							)
						)
					)
				)
				(pin bidirectional line
					(at 0 -22.86 0)
					(length 2.54)
					(name "CK+"
						(effects
							(font
								(size 1.27 1.27)
							)
						)
					)
					(number "10"
						(effects
							(font
								(size 1.27 1.27)
							)
						)
					)
				)
				(pin bidirectional line
					(at 0 -25.4 0)
					(length 2.54)
					(name "CK-"
						(effects
							(font
								(size 1.27 1.27)
							)
						)
					)
					(number "12"
						(effects
							(font
								(size 1.27 1.27)
							)
						)
					)
				)
				(pin bidirectional line
					(at 0 -30.48 0)
					(length 2.54)
					(name "SCL"
						(effects
							(font
								(size 1.27 1.27)
							)
						)
					)
					(number "15"
						(effects
							(font
								(size 1.27 1.27)
							)
						)
					)
				)
				(pin bidirectional line
					(at 0 -33.02 0)
					(length 2.54)
					(name "SDA"
						(effects
							(font
								(size 1.27 1.27)
							)
						)
					)
					(number "16"
						(effects
							(font
								(size 1.27 1.27)
							)
						)
					)
				)
				(pin bidirectional line
					(at 0 -38.1 0)
					(length 2.54)
					(name "CEC"
						(effects
							(font
								(size 1.27 1.27)
							)
						)
					)
					(number "13"
						(effects
							(font
								(size 1.27 1.27)
							)
						)
					)
				)
				(pin bidirectional line
					(at 0 -43.18 0)
					(length 2.54)
					(name "HPD/HEAC-"
						(effects
							(font
								(size 1.27 1.27)
							)
						)
					)
					(number "19"
						(effects
							(font
								(size 1.27 1.27)
							)
						)
					)
					(alternate "HEAC-" passive line)
					(alternate "HPD" passive line)
				)
				(pin bidirectional line
					(at 0 -45.72 0)
					(length 2.54)
					(name "UTILITY/HEAC+"
						(effects
							(font
								(size 1.27 1.27)
							)
						)
					)
					(number "14"
						(effects
							(font
								(size 1.27 1.27)
							)
						)
					)
					(alternate "HEAC+" passive line)
					(alternate "UTILITY" passive line)
				)
				(pin power_in line
					(at 0 -50.8 0)
					(length 2.54)
					(name "+5V"
						(effects
							(font
								(size 1.27 1.27)
							)
						)
					)
					(number "18"
						(effects
							(font
								(size 1.27 1.27)
							)
						)
					)
				)
				(pin passive line
					(at 25.4 -38.1 180)
					(length 2.54)
					(name "D2S"
						(effects
							(font
								(size 1.27 1.27)
							)
						)
					)
					(number "2"
						(effects
							(font
								(size 1.27 1.27)
							)
						)
					)
				)
				(pin passive line
					(at 25.4 -40.64 180)
					(length 2.54)
					(name "D1S"
						(effects
							(font
								(size 1.27 1.27)
							)
						)
					)
					(number "5"
						(effects
							(font
								(size 1.27 1.27)
							)
						)
					)
				)
				(pin passive line
					(at 25.4 -43.18 180)
					(length 2.54)
					(name "D0S"
						(effects
							(font
								(size 1.27 1.27)
							)
						)
					)
					(number "8"
						(effects
							(font
								(size 1.27 1.27)
							)
						)
					)
				)
				(pin passive line
					(at 25.4 -45.72 180)
					(length 2.54)
					(name "CKS"
						(effects
							(font
								(size 1.27 1.27)
							)
						)
					)
					(number "11"
						(effects
							(font
								(size 1.27 1.27)
							)
						)
					)
				)
				(pin power_in line
					(at 25.4 -48.26 180)
					(length 2.54)
					(name "GND"
						(effects
							(font
								(size 1.27 1.27)
							)
						)
					)
					(number "17"
						(effects
							(font
								(size 1.27 1.27)
							)
						)
					)
				)
				(pin passive line
					(at 25.4 -50.8 180)
					(length 2.54)
					(name "SH"
						(effects
							(font
								(size 1.27 1.27)
							)
						)
					)
					(number "SH"
						(effects
							(font
								(size 1.27 1.27)
							)
						)
					)
				)
			)
		)
	(symbol "antmicroWire2BoardConnectors:JST_SH_1x2_SM02B-SRSS-TB-LF-SN"
			(exclude_from_sim no)
			(in_bom yes)
			(on_board yes)
			(property "Reference" "J"
				(at 26.67 -3.81 0)
				(effects
					(font
						(size 1.27 1.27)
						(thickness 0.15)
					)
					(justify left bottom)
				)
			)
			(property "Value" "JST_SH_1x2_SM02B-SRSS-TB-LF-SN"
				(at 26.67 -6.35 0)
				(effects
					(font
						(size 1.27 1.27)
						(thickness 0.15)
					)
					(justify left bottom)
					(hide yes)
				)
			)
			(property "Footprint" "antmicro-footprints:Conn_JST_SH_1x2_SM02B-SRSS-TB-LF-SN"
				(at 26.67 -8.89 0)
				(effects
					(font
						(size 1.27 1.27)
						(thickness 0.15)
					)
					(justify left bottom)
					(hide yes)
				)
			)
			(property "Datasheet" "https://www.jst-mfg.com/product/pdf/eng/eSH.pdf"
				(at 26.67 -11.43 0)
				(effects
					(font
						(size 1.27 1.27)
						(thickness 0.15)
					)
					(justify left bottom)
					(hide yes)
				)
			)
			(property "Description" "Rectangular connector, header"
				(at 0 0 0)
				(effects
					(font
						(size 1.27 1.27)
					)
					(hide yes)
				)
			)
			(property "MPN" "SM02B-SRSS-TB(LF)(SN)"
				(at 26.67 -13.97 0)
				(effects
					(font
						(size 1.27 1.27)
						(thickness 0.15)
					)
					(justify left bottom)
				)
			)
			(property "Manufacturer" "JST Automotive Connectors"
				(at 26.67 -16.51 0)
				(effects
					(font
						(size 1.27 1.27)
						(thickness 0.15)
					)
					(justify left bottom)
					(hide yes)
				)
			)
			(property "Author" "Antmicro"
				(at 26.67 -19.05 0)
				(effects
					(font
						(size 1.27 1.27)
						(thickness 0.15)
					)
					(justify left bottom)
					(hide yes)
				)
			)
			(property "License" "Apache-2.0"
				(at 26.67 -21.59 0)
				(effects
					(font
						(size 1.27 1.27)
						(thickness 0.15)
					)
					(justify left bottom)
					(hide yes)
				)
			)
			(property "ki_keywords" "CONNECTOR, SMT"
				(at 0 0 0)
				(effects
					(font
						(size 1.27 1.27)
					)
					(hide yes)
				)
			)
			(symbol "JST_SH_1x2_SM02B-SRSS-TB-LF-SN_1_1"
				(rectangle
					(start 2.54 2.54)
					(end 5.08 -7.62)
					(stroke
						(width 0.254)
						(type default)
					)
					(fill
						(type background)
					)
				)
				(rectangle
					(start 2.54 0.127)
					(end 3.81 -0.127)
					(stroke
						(width 0.254)
						(type default)
					)
					(fill
						(type background)
					)
				)
				(rectangle
					(start 2.54 -2.413)
					(end 3.81 -2.667)
					(stroke
						(width 0.254)
						(type default)
					)
					(fill
						(type background)
					)
				)
				(rectangle
					(start 2.54 -4.953)
					(end 3.81 -5.207)
					(stroke
						(width 0.254)
						(type default)
					)
					(fill
						(type background)
					)
				)
				(pin passive line
					(at 0 0 0)
					(length 2.54)
					(name "~"
						(effects
							(font
								(size 1.27 1.27)
							)
						)
					)
					(number "1"
						(effects
							(font
								(size 1.27 1.27)
							)
						)
					)
				)
				(pin passive line
					(at 0 -2.54 0)
					(length 2.54)
					(name "~"
						(effects
							(font
								(size 1.27 1.27)
							)
						)
					)
					(number "2"
						(effects
							(font
								(size 1.27 1.27)
							)
						)
					)
				)
				(pin passive line
					(at 0 -5.08 0)
					(length 2.54)
					(name "~"
						(effects
							(font
								(size 1.27 1.27)
							)
						)
					)
					(number "MP"
						(effects
							(font
								(size 1.27 1.27)
							)
						)
					)
				)
			)
		)
	(symbol "antmicroWire2BoardConnectors:JST_SH_1x4_SM04B-SRSS-TB-LF-SN"
			(exclude_from_sim no)
			(in_bom yes)
			(on_board yes)
			(property "Reference" "J"
				(at 26.67 -2.54 0)
				(effects
					(font
						(size 1.27 1.27)
						(thickness 0.15)
					)
					(justify left bottom)
				)
			)
			(property "Value" "JST_SH_1x4_SM04B-SRSS-TB-LF-SN"
				(at 26.67 -7.62 0)
				(effects
					(font
						(size 1.27 1.27)
						(thickness 0.15)
					)
					(justify left bottom)
					(hide yes)
				)
			)
			(property "Footprint" "antmicro-footprints:Conn_JST_SH_1x4_SM04B-SRSS-TB-LF-SN"
				(at 26.67 -10.16 0)
				(effects
					(font
						(size 1.27 1.27)
						(thickness 0.15)
					)
					(justify left bottom)
					(hide yes)
				)
			)
			(property "Datasheet" "https://www.jst-mfg.com/product/pdf/eng/eSH.pdf"
				(at 26.67 -12.7 0)
				(effects
					(font
						(size 1.27 1.27)
						(thickness 0.15)
					)
					(justify left bottom)
					(hide yes)
				)
			)
			(property "Description" "Pin Header, Right Angle, Wire-to-Board, 1 mm, 1 Rows, 4 Contacts, Surface Mount Right Angle, SH"
				(at 0 0 0)
				(effects
					(font
						(size 1.27 1.27)
					)
					(hide yes)
				)
			)
			(property "MPN" "SM04B-SRSS-TB(LF)(SN)"
				(at 26.67 -5.08 0)
				(effects
					(font
						(size 1.27 1.27)
						(thickness 0.15)
					)
					(justify left bottom)
				)
			)
			(property "Manufacturer" "JST Automotive Connectors"
				(at 26.67 -15.24 0)
				(effects
					(font
						(size 1.27 1.27)
						(thickness 0.15)
					)
					(justify left bottom)
					(hide yes)
				)
			)
			(property "Author" "Antmicro"
				(at 26.67 -17.78 0)
				(effects
					(font
						(size 1.27 1.27)
						(thickness 0.15)
					)
					(justify left bottom)
					(hide yes)
				)
			)
			(property "License" "Apache-2.0"
				(at 26.67 -20.32 0)
				(effects
					(font
						(size 1.27 1.27)
						(thickness 0.15)
					)
					(justify left bottom)
					(hide yes)
				)
			)
			(property "ki_keywords" "VERTICAL, SMT, WIRE-BOARD, CONNECTOR, MALE, HEADER"
				(at 0 0 0)
				(effects
					(font
						(size 1.27 1.27)
					)
					(hide yes)
				)
			)
			(symbol "JST_SH_1x4_SM04B-SRSS-TB-LF-SN_1_1"
				(rectangle
					(start 2.54 2.54)
					(end 5.08 -12.7)
					(stroke
						(width 0.254)
						(type default)
					)
					(fill
						(type background)
					)
				)
				(rectangle
					(start 2.54 0.127)
					(end 3.81 -0.127)
					(stroke
						(width 0.254)
						(type default)
					)
					(fill
						(type background)
					)
				)
				(rectangle
					(start 2.54 -2.413)
					(end 3.81 -2.667)
					(stroke
						(width 0.254)
						(type default)
					)
					(fill
						(type background)
					)
				)
				(rectangle
					(start 2.54 -4.953)
					(end 3.81 -5.207)
					(stroke
						(width 0.254)
						(type default)
					)
					(fill
						(type background)
					)
				)
				(rectangle
					(start 2.54 -7.493)
					(end 3.81 -7.747)
					(stroke
						(width 0.254)
						(type default)
					)
					(fill
						(type background)
					)
				)
				(rectangle
					(start 2.54 -10.033)
					(end 3.81 -10.287)
					(stroke
						(width 0.254)
						(type default)
					)
					(fill
						(type background)
					)
				)
				(pin passive line
					(at 0 0 0)
					(length 2.54)
					(name "~"
						(effects
							(font
								(size 1.27 1.27)
							)
						)
					)
					(number "1"
						(effects
							(font
								(size 1.27 1.27)
							)
						)
					)
				)
				(pin passive line
					(at 0 -2.54 0)
					(length 2.54)
					(name "~"
						(effects
							(font
								(size 1.27 1.27)
							)
						)
					)
					(number "2"
						(effects
							(font
								(size 1.27 1.27)
							)
						)
					)
				)
				(pin passive line
					(at 0 -5.08 0)
					(length 2.54)
					(name "~"
						(effects
							(font
								(size 1.27 1.27)
							)
						)
					)
					(number "3"
						(effects
							(font
								(size 1.27 1.27)
							)
						)
					)
				)
				(pin passive line
					(at 0 -7.62 0)
					(length 2.54)
					(name "~"
						(effects
							(font
								(size 1.27 1.27)
							)
						)
					)
					(number "4"
						(effects
							(font
								(size 1.27 1.27)
							)
						)
					)
				)
				(pin passive line
					(at 0 -10.16 0)
					(length 2.54)
					(name "~"
						(effects
							(font
								(size 1.27 1.27)
							)
						)
					)
					(number "MP"
						(effects
							(font
								(size 1.27 1.27)
							)
						)
					)
				)
			)
		)
	(symbol "antmicroWire2BoardConnectors:Molex_Nano-Fit_1x2_SMD_1054301202"
			(exclude_from_sim no)
			(in_bom yes)
			(on_board yes)
			(property "Reference" "J"
				(at 26.67 -2.54 0)
				(effects
					(font
						(size 1.27 1.27)
						(thickness 0.15)
					)
					(justify left bottom)
				)
			)
			(property "Value" "Molex_Nano-Fit_1x2_SMD_1054301202"
				(at 26.67 -7.62 0)
				(effects
					(font
						(size 1.27 1.27)
						(thickness 0.15)
					)
					(justify left bottom)
					(hide yes)
				)
			)
			(property "Footprint" "antmicro-footprints:Conn_Molex_Nano-Fit_1x2_SMD_1054301202"
				(at 26.67 -10.16 0)
				(effects
					(font
						(size 1.27 1.27)
						(thickness 0.15)
					)
					(justify left bottom)
					(hide yes)
				)
			)
			(property "Datasheet" "https://www.farnell.com/cad/3578051.pdf"
				(at 26.67 -12.7 0)
				(effects
					(font
						(size 1.27 1.27)
						(thickness 0.15)
					)
					(justify left bottom)
					(hide yes)
				)
			)
			(property "Description" "Pin Header, Pitch 2.5 mm, 1 Row, 2 Contacts, Nano-Fit"
				(at 0 0 0)
				(effects
					(font
						(size 1.27 1.27)
					)
					(hide yes)
				)
			)
			(property "Manufacturer" "Molex"
				(at 26.67 -15.24 0)
				(effects
					(font
						(size 1.27 1.27)
						(thickness 0.15)
					)
					(justify left bottom)
					(hide yes)
				)
			)
			(property "MPN" "105430-1202"
				(at 26.67 -5.08 0)
				(effects
					(font
						(size 1.27 1.27)
						(thickness 0.15)
					)
					(justify left bottom)
				)
			)
			(property "Author" "Antmicro"
				(at 26.67 -17.78 0)
				(effects
					(font
						(size 1.27 1.27)
						(thickness 0.15)
					)
					(justify left bottom)
					(hide yes)
				)
			)
			(property "License" "Apache-2.0"
				(at 26.67 -20.32 0)
				(effects
					(font
						(size 1.27 1.27)
						(thickness 0.15)
					)
					(justify left bottom)
					(hide yes)
				)
			)
			(property "ki_keywords" "CONNECTOR, HEADER, HORIZONTAL, SMT"
				(at 0 0 0)
				(effects
					(font
						(size 1.27 1.27)
					)
					(hide yes)
				)
			)
			(symbol "Molex_Nano-Fit_1x2_SMD_1054301202_1_1"
				(rectangle
					(start 2.54 2.54)
					(end 6.35 -7.62)
					(stroke
						(width 0.254)
						(type default)
					)
					(fill
						(type background)
					)
				)
				(rectangle
					(start 2.54 -0.254)
					(end 4.1402 0.381)
					(stroke
						(width 0.254)
						(type default)
					)
					(fill
						(type background)
					)
				)
				(rectangle
					(start 2.54 -2.794)
					(end 4.1402 -2.159)
					(stroke
						(width 0.254)
						(type default)
					)
					(fill
						(type background)
					)
				)
				(rectangle
					(start 2.54 -5.334)
					(end 4.1402 -4.699)
					(stroke
						(width 0.254)
						(type default)
					)
					(fill
						(type background)
					)
				)
				(pin passive line
					(at 0 0 0)
					(length 2.54)
					(name "~"
						(effects
							(font
								(size 1.27 1.27)
							)
						)
					)
					(number "1"
						(effects
							(font
								(size 1.27 1.27)
							)
						)
					)
				)
				(pin passive line
					(at 0 -2.54 0)
					(length 2.54)
					(name "~"
						(effects
							(font
								(size 1.27 1.27)
							)
						)
					)
					(number "2"
						(effects
							(font
								(size 1.27 1.27)
							)
						)
					)
				)
				(pin passive line
					(at 0 -5.08 0)
					(length 2.54)
					(name "~"
						(effects
							(font
								(size 1.27 1.27)
							)
						)
					)
					(number "MP"
						(effects
							(font
								(size 1.27 1.27)
							)
						)
					)
				)
			)
		)
	(symbol "antmicropower:+1V8"
			(power)
			(pin_numbers
				(hide yes)
			)
			(pin_names
				(hide yes)
			)
			(exclude_from_sim no)
			(in_bom yes)
			(on_board yes)
			(property "Reference" "#PWR"
				(at 15.24 -2.54 0)
				(effects
					(font
						(size 1.27 1.27)
						(thickness 0.15)
					)
					(justify left bottom)
					(hide yes)
				)
			)
			(property "Value" "+1V8"
				(at -3.175 2.54 0)
				(effects
					(font
						(size 1.27 1.27)
						(thickness 0.15)
					)
					(justify left bottom)
				)
			)
			(property "Footprint" ""
				(at 15.24 -7.62 0)
				(effects
					(font
						(size 1.27 1.27)
						(thickness 0.15)
					)
					(justify left bottom)
					(hide yes)
				)
			)
			(property "Datasheet" ""
				(at 15.24 -10.16 0)
				(effects
					(font
						(size 1.27 1.27)
						(thickness 0.15)
					)
					(justify left bottom)
					(hide yes)
				)
			)
			(property "Description" ""
				(at 0 0 0)
				(effects
					(font
						(size 1.27 1.27)
					)
					(hide yes)
				)
			)
			(property "Author" "Antmicro"
				(at 15.24 -5.08 0)
				(effects
					(font
						(size 1.27 1.27)
						(thickness 0.15)
					)
					(justify left bottom)
					(hide yes)
				)
			)
			(property "License" "Apache-2.0"
				(at 15.24 -7.62 0)
				(effects
					(font
						(size 1.27 1.27)
						(thickness 0.15)
					)
					(justify left bottom)
					(hide yes)
				)
			)
			(symbol "+1V8_1_1"
				(polyline
					(pts
						(xy -0.762 1.27) (xy 0 2.54)
					)
					(stroke
						(width 0)
						(type default)
					)
					(fill
						(type background)
					)
				)
				(polyline
					(pts
						(xy 0 2.54) (xy 0.762 1.27)
					)
					(stroke
						(width 0)
						(type default)
					)
					(fill
						(type background)
					)
				)
				(polyline
					(pts
						(xy 0 0) (xy 0 2.54)
					)
					(stroke
						(width 0)
						(type default)
					)
					(fill
						(type background)
					)
				)
				(pin power_in line
					(at 0 0 90)
					(length 0)
					(hide yes)
					(name "+1V8"
						(effects
							(font
								(size 1.27 1.27)
							)
						)
					)
					(number "1"
						(effects
							(font
								(size 1.27 1.27)
							)
						)
					)
				)
			)
		)
	(symbol "antmicropower:+3V3"
			(power)
			(pin_numbers
				(hide yes)
			)
			(pin_names
				(hide yes)
			)
			(exclude_from_sim no)
			(in_bom yes)
			(on_board yes)
			(property "Reference" "#PWR"
				(at 15.24 0 0)
				(effects
					(font
						(size 1.27 1.27)
						(thickness 0.15)
					)
					(justify left bottom)
					(hide yes)
				)
			)
			(property "Value" "+3V3"
				(at -3.175 2.54 0)
				(effects
					(font
						(size 1.27 1.27)
						(thickness 0.15)
					)
					(justify left bottom)
				)
			)
			(property "Footprint" ""
				(at 15.24 -7.62 0)
				(effects
					(font
						(size 1.27 1.27)
						(thickness 0.15)
					)
					(justify left bottom)
					(hide yes)
				)
			)
			(property "Datasheet" ""
				(at 15.24 -10.16 0)
				(effects
					(font
						(size 1.27 1.27)
						(thickness 0.15)
					)
					(justify left bottom)
					(hide yes)
				)
			)
			(property "Description" ""
				(at 0 0 0)
				(effects
					(font
						(size 1.27 1.27)
					)
					(hide yes)
				)
			)
			(property "Author" "Antmicro"
				(at 15.24 -2.54 0)
				(effects
					(font
						(size 1.27 1.27)
						(thickness 0.15)
					)
					(justify left bottom)
					(hide yes)
				)
			)
			(property "License" "Apache-2.0"
				(at 15.24 -5.08 0)
				(effects
					(font
						(size 1.27 1.27)
						(thickness 0.15)
					)
					(justify left bottom)
					(hide yes)
				)
			)
			(symbol "+3V3_0_1"
				(polyline
					(pts
						(xy 0 2.54) (xy -0.762 1.27)
					)
					(stroke
						(width 0)
						(type default)
					)
					(fill
						(type none)
					)
				)
				(polyline
					(pts
						(xy 0 2.54) (xy 0.762 1.27)
					)
					(stroke
						(width 0)
						(type default)
					)
					(fill
						(type none)
					)
				)
				(polyline
					(pts
						(xy 0 0) (xy 0 2.54)
					)
					(stroke
						(width 0)
						(type default)
					)
					(fill
						(type none)
					)
				)
			)
			(symbol "+3V3_1_1"
				(pin power_in line
					(at 0 0 90)
					(length 0)
					(hide yes)
					(name "+3V3"
						(effects
							(font
								(size 1.27 1.27)
							)
						)
					)
					(number "1"
						(effects
							(font
								(size 1.27 1.27)
							)
						)
					)
				)
			)
		)
	(symbol "antmicropower:+5V"
			(power)
			(pin_numbers
				(hide yes)
			)
			(pin_names
				(hide yes)
			)
			(exclude_from_sim no)
			(in_bom yes)
			(on_board yes)
			(property "Reference" "#PWR"
				(at 15.24 -2.54 0)
				(effects
					(font
						(size 1.27 1.27)
						(thickness 0.15)
					)
					(justify left bottom)
					(hide yes)
				)
			)
			(property "Value" "+5V"
				(at 15.24 -5.08 0)
				(effects
					(font
						(size 1.27 1.27)
						(thickness 0.15)
					)
					(justify left bottom)
				)
			)
			(property "Footprint" ""
				(at 15.24 -7.62 0)
				(effects
					(font
						(size 1.27 1.27)
						(thickness 0.15)
					)
					(justify left bottom)
					(hide yes)
				)
			)
			(property "Datasheet" ""
				(at 15.24 -10.16 0)
				(effects
					(font
						(size 1.27 1.27)
						(thickness 0.15)
					)
					(justify left bottom)
					(hide yes)
				)
			)
			(property "Description" ""
				(at 0 0 0)
				(effects
					(font
						(size 1.27 1.27)
					)
					(hide yes)
				)
			)
			(property "Author" "Antmicro"
				(at 15.24 -7.62 0)
				(effects
					(font
						(size 1.27 1.27)
						(thickness 0.15)
					)
					(justify left bottom)
					(hide yes)
				)
			)
			(property "License" "Apache-2.0"
				(at 15.24 -10.16 0)
				(effects
					(font
						(size 1.27 1.27)
						(thickness 0.15)
					)
					(justify left bottom)
					(hide yes)
				)
			)
			(symbol "+5V_1_1"
				(polyline
					(pts
						(xy -0.762 1.27) (xy 0 2.54)
					)
					(stroke
						(width 0)
						(type default)
					)
					(fill
						(type background)
					)
				)
				(polyline
					(pts
						(xy 0 2.54) (xy 0.762 1.27)
					)
					(stroke
						(width 0)
						(type default)
					)
					(fill
						(type background)
					)
				)
				(polyline
					(pts
						(xy 0 0) (xy 0 2.54)
					)
					(stroke
						(width 0)
						(type default)
					)
					(fill
						(type background)
					)
				)
				(pin power_in line
					(at 0 0 90)
					(length 0)
					(name "+5V"
						(effects
							(font
								(size 1.27 1.27)
							)
						)
					)
					(number "1"
						(effects
							(font
								(size 1.27 1.27)
							)
						)
					)
				)
			)
		)
	(symbol "antmicropower:GND"
			(power)
			(pin_numbers
				(hide yes)
			)
			(pin_names
				(hide yes)
			)
			(exclude_from_sim no)
			(in_bom yes)
			(on_board yes)
			(property "Reference" "#PWR"
				(at 8.89 -2.54 0)
				(effects
					(font
						(size 1.27 1.27)
						(thickness 0.15)
					)
					(justify left bottom)
					(hide yes)
				)
			)
			(property "Value" "GND"
				(at 8.89 -5.08 0)
				(effects
					(font
						(size 1.27 1.27)
						(thickness 0.15)
					)
					(justify left bottom)
				)
			)
			(property "Footprint" ""
				(at 8.89 -7.62 0)
				(effects
					(font
						(size 1.27 1.27)
						(thickness 0.15)
					)
					(justify left bottom)
					(hide yes)
				)
			)
			(property "Datasheet" ""
				(at 8.89 -12.7 0)
				(effects
					(font
						(size 1.27 1.27)
						(thickness 0.15)
					)
					(justify left bottom)
					(hide yes)
				)
			)
			(property "Description" ""
				(at 0 0 0)
				(effects
					(font
						(size 1.27 1.27)
					)
					(hide yes)
				)
			)
			(property "Author" "Antmicro"
				(at 8.89 -7.62 0)
				(effects
					(font
						(size 1.27 1.27)
						(thickness 0.15)
					)
					(justify left bottom)
					(hide yes)
				)
			)
			(property "License" "Apache-2.0"
				(at 8.89 -10.16 0)
				(effects
					(font
						(size 1.27 1.27)
						(thickness 0.15)
					)
					(justify left bottom)
					(hide yes)
				)
			)
			(symbol "GND_1_1"
				(polyline
					(pts
						(xy 0 0) (xy 0 -1.27) (xy 1.27 -1.27) (xy 0 -2.54) (xy -1.27 -1.27) (xy 0 -1.27)
					)
					(stroke
						(width 0)
						(type default)
					)
					(fill
						(type none)
					)
				)
				(pin power_in line
					(at 0 0 270)
					(length 0)
					(name "GND"
						(effects
							(font
								(size 1.27 1.27)
							)
						)
					)
					(number "1"
						(effects
							(font
								(size 1.27 1.27)
							)
						)
					)
				)
			)
		)
	(symbol "antmicropower:GNDD"
			(power)
			(pin_numbers
				(hide yes)
			)
			(pin_names
				(hide yes)
			)
			(exclude_from_sim no)
			(in_bom yes)
			(on_board yes)
			(property "Reference" "#PWR"
				(at 15.24 -2.54 0)
				(effects
					(font
						(size 1.27 1.27)
						(thickness 0.15)
					)
					(justify left bottom)
					(hide yes)
				)
			)
			(property "Value" "GNDD"
				(at 15.24 -5.08 0)
				(effects
					(font
						(size 1.27 1.27)
						(thickness 0.15)
					)
					(justify left bottom)
				)
			)
			(property "Footprint" ""
				(at 15.24 -10.16 0)
				(effects
					(font
						(size 1.27 1.27)
						(thickness 0.15)
					)
					(justify left bottom)
					(hide yes)
				)
			)
			(property "Datasheet" ""
				(at 15.24 -12.7 0)
				(effects
					(font
						(size 1.27 1.27)
						(thickness 0.15)
					)
					(justify left bottom)
					(hide yes)
				)
			)
			(property "Description" ""
				(at 0 0 0)
				(effects
					(font
						(size 1.27 1.27)
					)
					(hide yes)
				)
			)
			(property "Author" "Antmicro"
				(at 15.24 -7.62 0)
				(effects
					(font
						(size 1.27 1.27)
						(thickness 0.15)
					)
					(justify left bottom)
					(hide yes)
				)
			)
			(property "License" "Apache-2.0"
				(at 15.24 -10.16 0)
				(effects
					(font
						(size 1.27 1.27)
						(thickness 0.15)
					)
					(justify left bottom)
					(hide yes)
				)
			)
			(symbol "GNDD_1_1"
				(rectangle
					(start -1.27 -1.524)
					(end 1.27 -2.032)
					(stroke
						(width 0)
						(type default)
					)
					(fill
						(type outline)
					)
				)
				(polyline
					(pts
						(xy 0 0) (xy 0 -1.524)
					)
					(stroke
						(width 0)
						(type default)
					)
					(fill
						(type background)
					)
				)
				(pin power_in line
					(at 0 0 270)
					(length 0)
					(name "GNDD"
						(effects
							(font
								(size 1.27 1.27)
							)
						)
					)
					(number "1"
						(effects
							(font
								(size 1.27 1.27)
							)
						)
					)
				)
			)
		)
	(symbol "antmicropower:PWR_FLAG"
			(power)
			(pin_numbers
				(hide yes)
			)
			(pin_names
				(offset 0)
				(hide yes)
			)
			(exclude_from_sim no)
			(in_bom yes)
			(on_board yes)
			(property "Reference" "#FLG"
				(at 0 1.905 0)
				(effects
					(font
						(size 1.27 1.27)
					)
					(hide yes)
				)
			)
			(property "Value" "PWR_FLAG"
				(at 0 3.81 0)
				(effects
					(font
						(size 1.27 1.27)
					)
				)
			)
			(property "Footprint" ""
				(at 0 0 0)
				(effects
					(font
						(size 1.27 1.27)
					)
					(hide yes)
				)
			)
			(property "Datasheet" ""
				(at 0 0 0)
				(effects
					(font
						(size 1.27 1.27)
					)
					(hide yes)
				)
			)
			(property "Description" ""
				(at 0 0 0)
				(effects
					(font
						(size 1.27 1.27)
					)
					(hide yes)
				)
			)
			(symbol "PWR_FLAG_0_0"
				(pin power_out line
					(at 0 0 90)
					(length 0)
					(name "pwr"
						(effects
							(font
								(size 1.27 1.27)
							)
						)
					)
					(number "1"
						(effects
							(font
								(size 1.27 1.27)
							)
						)
					)
				)
			)
			(symbol "PWR_FLAG_0_1"
				(polyline
					(pts
						(xy 0 0) (xy 0 1.27) (xy -1.016 1.905) (xy 0 2.54) (xy 1.016 1.905) (xy 0 1.27)
					)
					(stroke
						(width 0)
						(type default)
					)
					(fill
						(type none)
					)
				)
			)
		)
	(symbol "antmicropower:VCC"
			(power)
			(pin_names
				(offset 0)
			)
			(exclude_from_sim no)
			(in_bom yes)
			(on_board yes)
			(property "Reference" "#PWR"
				(at 0 -3.81 0)
				(effects
					(font
						(size 1.27 1.27)
					)
					(hide yes)
				)
			)
			(property "Value" "VCC"
				(at 0 3.81 0)
				(effects
					(font
						(size 1.27 1.27)
					)
				)
			)
			(property "Footprint" ""
				(at 0 0 0)
				(effects
					(font
						(size 1.27 1.27)
					)
					(hide yes)
				)
			)
			(property "Datasheet" ""
				(at 0 0 0)
				(effects
					(font
						(size 1.27 1.27)
					)
					(hide yes)
				)
			)
			(property "Description" ""
				(at 0 0 0)
				(effects
					(font
						(size 1.27 1.27)
					)
					(hide yes)
				)
			)
			(symbol "VCC_0_1"
				(polyline
					(pts
						(xy -0.762 1.27) (xy 0 2.54)
					)
					(stroke
						(width 0)
						(type default)
					)
					(fill
						(type none)
					)
				)
				(polyline
					(pts
						(xy 0 2.54) (xy 0.762 1.27)
					)
					(stroke
						(width 0)
						(type default)
					)
					(fill
						(type none)
					)
				)
				(polyline
					(pts
						(xy 0 0) (xy 0 2.54)
					)
					(stroke
						(width 0)
						(type default)
					)
					(fill
						(type none)
					)
				)
			)
			(symbol "VCC_1_1"
				(pin power_in line
					(at 0 0 90)
					(length 0)
					(hide yes)
					(name "VCC"
						(effects
							(font
								(size 1.27 1.27)
							)
						)
					)
					(number "1"
						(effects
							(font
								(size 1.27 1.27)
							)
						)
					)
				)
			)
		)
)
